FILE_TYPE = MACRO_DRAWING;
SET COLOR_WIRE YELLOW;
SET COLOR_PROP ORANGE;
SET COLOR_DOT WHITE;
SET COLOR_ARC YELLOW;
SET COLOR_BODY GREEN;
SET COLOR_NOTE PURPLE;
SET PROP_DISPLAY VALUE;
SET PAGE_NUMBER P233;
FORCEADD OFFPAGE..1
(-6575 -2025);
FORCEPROP 2 LAST $XR0 215 
J 0
(-6827 -2025);
DISPLAY 0.638298 (-6827 -2025);
PAINT MONO (-6827 -2025);
FORCEPROP 2 LAST $XR1 151 
J 0
(-6947 -2025);
DISPLAY 0.638298 (-6947 -2025);
PAINT MONO (-6947 -2025);
FORCEPROP 1 LAST COMMENT_BODY TRUE
J 0
(-6450 -2125);
DISPLAY 0.872340 (-6450 -2125);
PAINT GREEN (-6450 -2125);
DISPLAY INVISIBLE (-6450 -2125);
FORCEPROP 1 LAST OFFPAGE TRUE
J 0
(-6250 -2150);
DISPLAY 0.872340 (-6250 -2150);
DISPLAY INVISIBLE (-6250 -2150);
FORCEPROP 2 LAST CDS_LIB standard
J 0
(-6575 -2025);
DISPLAY INVISIBLE (-6575 -2025);
FORCEPROP 2 LAST PATH I1
J 0
(-6825 -1975);
DISPLAY 1.021277 (-6825 -1975);
DISPLAY INVISIBLE (-6825 -1975);
FORCEADD Q_RES..1
(-4100 -2025);
FORCEPROP 1 LAST PART_NUMBER CS03322FB03
J 0
(-4225 -1975);
DISPLAY 0.638298 (-4225 -1975);
DISPLAY INVISIBLE (-4225 -1975);
FORCEPROP 1 LAST MATERIAL CHIP
J 0
(-3975 -2025);
DISPLAY 0.638298 (-3975 -2025);
FORCEPROP 1 LAST TOLERANCE 1%
J 0
(-3900 -2050);
DISPLAY 0.510638 (-3900 -2050);
FORCEPROP 1 LAST PACK_TYPE 0402LF
J 0
(-3800 -2050);
DISPLAY 0.510638 (-3800 -2050);
FORCEPROP 1 LAST VALUE 33.2
J 2
(-3925 -2050);
DISPLAY 0.510638 (-3925 -2050);
FORCEPROP 1 LAST LOCATION R2796
J 0
(-4350 -2025);
DISPLAY 0.638298 (-4350 -2025);
FORCEPROP 1 LASTPIN (-4200 -2025) $PN 1
J 0
(-4188 -2013);
DISPLAY 0.787234 (-4188 -2013);
PAINT MONO (-4188 -2013);
FORCEPROP 1 LASTPIN (-4000 -2025) $PN 2
J 0
(-4038 -2013);
DISPLAY 0.787234 (-4038 -2013);
PAINT MONO (-4038 -2013);
FORCEPROP 2 LAST CDS_LIB pure_quanta
J 0
(-4100 -2025);
DISPLAY INVISIBLE (-4100 -2025);
FORCEPROP 1 LAST WATTAGE 1/16W
J 2
(-3900 -1925);
DISPLAY 0.638298 (-3900 -1925);
DISPLAY INVISIBLE (-3900 -1925);
FORCEPROP 1 LAST PATH I10
J 0
(-4150 -1875);
DISPLAY 0.978723 (-4150 -1875);
PAINT WHITE (-4150 -1875);
DISPLAY INVISIBLE (-4150 -1875);
FORCEPROP 0 LAST $SEC 1
J 0
(-4025 -1975);
DISPLAY 0.680851 (-4025 -1975);
PAINT MONO (-4025 -1975);
DISPLAY INVISIBLE (-4025 -1975);
FORCEPROP 0 LAST CDS_SEC 1
J 0
(-4025 -1975);
DISPLAY 1.021277 (-4025 -1975);
DISPLAY INVISIBLE (-4025 -1975);
FORCEADD UNIVERSAL_GND..1
(-3825 25);
FORCEPROP 3 LASTPIN (-3825 75) SIG_NAME GND\g
J 0
(-3815 85);
DISPLAY 0.659574 (-3815 85);
PAINT MONO (-3815 85);
DISPLAY INVISIBLE (-3815 85);
FORCEPROP 2 LAST CDS_LIB logical_power
J 0
(-3825 25);
DISPLAY INVISIBLE (-3825 25);
FORCEPROP 1 LAST HDL_POWER GND
J 1
(-3800 -50);
DISPLAY 0.872340 (-3800 -50);
PAINT GREEN (-3800 -50);
DISPLAY INVISIBLE (-3800 -50);
FORCEPROP 1 LAST PATH I11
J 0
(-3750 25);
DISPLAY 0.872340 (-3750 25);
PAINT AQUA (-3750 25);
DISPLAY INVISIBLE (-3750 25);
FORCEADD CONN60_101062636003K02LF..1
(-3200 1150);
FORCEPROP 1 LAST PART_NUMBER DFHD60MR024
J 0
(-3450 2219);
DISPLAY 0.723404 (-3450 2219);
PAINT GREEN (-3450 2219);
DISPLAY INVISIBLE (-3450 2219);
FORCEPROP 1 LAST MATERIAL IO
J 0
(-3447 2167);
DISPLAY 0.723404 (-3447 2167);
PAINT GREEN (-3447 2167);
FORCEPROP 2 LAST PART_TYPE THLF
J 0
(-3450 2375);
DISPLAY 1.021277 (-3450 2375);
FORCEPROP 2 LAST VALUE CONN60_10106263-6003K02LF
J 0
(-3450 2325);
DISPLAY 1.021277 (-3450 2325);
FORCEPROP 1 LAST LOCATION J45
J 0
(-3450 2275);
DISPLAY 0.723404 (-3450 2275);
PAINT GREEN (-3450 2275);
FORCEPROP 0 LASTPIN (-3600 2050) $PN A1
J 2
(-3610 2060);
DISPLAY 0.680851 (-3610 2060);
PAINT MONO (-3610 2060);
FORCEPROP 0 LASTPIN (-3600 2000) $PN A2
J 2
(-3610 2010);
DISPLAY 0.680851 (-3610 2010);
PAINT MONO (-3610 2010);
FORCEPROP 0 LASTPIN (-3600 1950) $PN A3
J 2
(-3610 1960);
DISPLAY 0.680851 (-3610 1960);
PAINT MONO (-3610 1960);
FORCEPROP 0 LASTPIN (-3600 1900) $PN B1
J 2
(-3610 1910);
DISPLAY 0.680851 (-3610 1910);
PAINT MONO (-3610 1910);
FORCEPROP 0 LASTPIN (-3600 1850) $PN B2
J 2
(-3610 1860);
DISPLAY 0.680851 (-3610 1860);
PAINT MONO (-3610 1860);
FORCEPROP 0 LASTPIN (-3600 1800) $PN B3
J 2
(-3610 1810);
DISPLAY 0.680851 (-3610 1810);
PAINT MONO (-3610 1810);
FORCEPROP 0 LASTPIN (-2800 2050) $PN C1
J 0
(-2790 2060);
DISPLAY 0.680851 (-2790 2060);
PAINT MONO (-2790 2060);
FORCEPROP 0 LASTPIN (-2800 2000) $PN C2
J 0
(-2790 2010);
DISPLAY 0.680851 (-2790 2010);
PAINT MONO (-2790 2010);
FORCEPROP 0 LASTPIN (-2800 1950) $PN C3
J 0
(-2790 1960);
DISPLAY 0.680851 (-2790 1960);
PAINT MONO (-2790 1960);
FORCEPROP 0 LASTPIN (-2800 1900) $PN D1
J 0
(-2790 1910);
DISPLAY 0.680851 (-2790 1910);
PAINT MONO (-2790 1910);
FORCEPROP 0 LASTPIN (-2800 1850) $PN D2
J 0
(-2790 1860);
DISPLAY 0.680851 (-2790 1860);
PAINT MONO (-2790 1860);
FORCEPROP 0 LASTPIN (-2800 1800) $PN D3
J 0
(-2790 1810);
DISPLAY 0.680851 (-2790 1810);
PAINT MONO (-2790 1810);
FORCEPROP 0 LASTPIN (-3600 1650) $PN P1_1
J 2
(-3610 1660);
DISPLAY 0.680851 (-3610 1660);
PAINT MONO (-3610 1660);
FORCEPROP 0 LASTPIN (-3600 1600) $PN P1_2
J 2
(-3610 1610);
DISPLAY 0.680851 (-3610 1610);
PAINT MONO (-3610 1610);
FORCEPROP 0 LASTPIN (-3600 1550) $PN P1_3
J 2
(-3610 1560);
DISPLAY 0.680851 (-3610 1560);
PAINT MONO (-3610 1560);
FORCEPROP 0 LASTPIN (-3600 1500) $PN P1_4
J 2
(-3610 1510);
DISPLAY 0.680851 (-3610 1510);
PAINT MONO (-3610 1510);
FORCEPROP 0 LASTPIN (-3600 1450) $PN P1_5
J 2
(-3610 1460);
DISPLAY 0.680851 (-3610 1460);
PAINT MONO (-3610 1460);
FORCEPROP 0 LASTPIN (-3600 1400) $PN P1_6
J 2
(-3610 1410);
DISPLAY 0.680851 (-3610 1410);
PAINT MONO (-3610 1410);
FORCEPROP 0 LASTPIN (-3600 1350) $PN P1_7
J 2
(-3610 1360);
DISPLAY 0.680851 (-3610 1360);
PAINT MONO (-3610 1360);
FORCEPROP 0 LASTPIN (-3600 1300) $PN P1_8
J 2
(-3610 1310);
DISPLAY 0.680851 (-3610 1310);
PAINT MONO (-3610 1310);
FORCEPROP 0 LASTPIN (-3600 1150) $PN P2_1
J 2
(-3610 1160);
DISPLAY 0.680851 (-3610 1160);
PAINT MONO (-3610 1160);
FORCEPROP 0 LASTPIN (-3600 1100) $PN P2_2
J 2
(-3610 1110);
DISPLAY 0.680851 (-3610 1110);
PAINT MONO (-3610 1110);
FORCEPROP 0 LASTPIN (-3600 1050) $PN P2_3
J 2
(-3610 1060);
DISPLAY 0.680851 (-3610 1060);
PAINT MONO (-3610 1060);
FORCEPROP 0 LASTPIN (-3600 1000) $PN P2_4
J 2
(-3610 1010);
DISPLAY 0.680851 (-3610 1010);
PAINT MONO (-3610 1010);
FORCEPROP 0 LASTPIN (-3600 950) $PN P2_5
J 2
(-3610 960);
DISPLAY 0.680851 (-3610 960);
PAINT MONO (-3610 960);
FORCEPROP 0 LASTPIN (-3600 900) $PN P2_6
J 2
(-3610 910);
DISPLAY 0.680851 (-3610 910);
PAINT MONO (-3610 910);
FORCEPROP 0 LASTPIN (-3600 850) $PN P2_7
J 2
(-3610 860);
DISPLAY 0.680851 (-3610 860);
PAINT MONO (-3610 860);
FORCEPROP 0 LASTPIN (-3600 800) $PN P2_8
J 2
(-3610 810);
DISPLAY 0.680851 (-3610 810);
PAINT MONO (-3610 810);
FORCEPROP 0 LASTPIN (-3600 650) $PN P3_1
J 2
(-3610 660);
DISPLAY 0.680851 (-3610 660);
PAINT MONO (-3610 660);
FORCEPROP 0 LASTPIN (-3600 600) $PN P3_2
J 2
(-3610 610);
DISPLAY 0.680851 (-3610 610);
PAINT MONO (-3610 610);
FORCEPROP 0 LASTPIN (-3600 550) $PN P3_3
J 2
(-3610 560);
DISPLAY 0.680851 (-3610 560);
PAINT MONO (-3610 560);
FORCEPROP 0 LASTPIN (-3600 500) $PN P3_4
J 2
(-3610 510);
DISPLAY 0.680851 (-3610 510);
PAINT MONO (-3610 510);
FORCEPROP 0 LASTPIN (-3600 450) $PN P3_5
J 2
(-3610 460);
DISPLAY 0.680851 (-3610 460);
PAINT MONO (-3610 460);
FORCEPROP 0 LASTPIN (-3600 400) $PN P3_6
J 2
(-3610 410);
DISPLAY 0.680851 (-3610 410);
PAINT MONO (-3610 410);
FORCEPROP 0 LASTPIN (-3600 350) $PN P3_7
J 2
(-3610 360);
DISPLAY 0.680851 (-3610 360);
PAINT MONO (-3610 360);
FORCEPROP 0 LASTPIN (-3600 300) $PN P3_8
J 2
(-3610 310);
DISPLAY 0.680851 (-3610 310);
PAINT MONO (-3610 310);
FORCEPROP 0 LASTPIN (-2800 1650) $PN P4_1
J 0
(-2790 1660);
DISPLAY 0.680851 (-2790 1660);
PAINT MONO (-2790 1660);
FORCEPROP 0 LASTPIN (-2800 1600) $PN P4_2
J 0
(-2790 1610);
DISPLAY 0.680851 (-2790 1610);
PAINT MONO (-2790 1610);
FORCEPROP 0 LASTPIN (-2800 1550) $PN P4_3
J 0
(-2790 1560);
DISPLAY 0.680851 (-2790 1560);
PAINT MONO (-2790 1560);
FORCEPROP 0 LASTPIN (-2800 1500) $PN P4_4
J 0
(-2790 1510);
DISPLAY 0.680851 (-2790 1510);
PAINT MONO (-2790 1510);
FORCEPROP 0 LASTPIN (-2800 1450) $PN P4_5
J 0
(-2790 1460);
DISPLAY 0.680851 (-2790 1460);
PAINT MONO (-2790 1460);
FORCEPROP 0 LASTPIN (-2800 1400) $PN P4_6
J 0
(-2790 1410);
DISPLAY 0.680851 (-2790 1410);
PAINT MONO (-2790 1410);
FORCEPROP 0 LASTPIN (-2800 1350) $PN P4_7
J 0
(-2790 1360);
DISPLAY 0.680851 (-2790 1360);
PAINT MONO (-2790 1360);
FORCEPROP 0 LASTPIN (-2800 1300) $PN P4_8
J 0
(-2790 1310);
DISPLAY 0.680851 (-2790 1310);
PAINT MONO (-2790 1310);
FORCEPROP 0 LASTPIN (-2800 1150) $PN P5_1
J 0
(-2790 1160);
DISPLAY 0.680851 (-2790 1160);
PAINT MONO (-2790 1160);
FORCEPROP 0 LASTPIN (-2800 1100) $PN P5_2
J 0
(-2790 1110);
DISPLAY 0.680851 (-2790 1110);
PAINT MONO (-2790 1110);
FORCEPROP 0 LASTPIN (-2800 1050) $PN P5_3
J 0
(-2790 1060);
DISPLAY 0.680851 (-2790 1060);
PAINT MONO (-2790 1060);
FORCEPROP 0 LASTPIN (-2800 1000) $PN P5_4
J 0
(-2790 1010);
DISPLAY 0.680851 (-2790 1010);
PAINT MONO (-2790 1010);
FORCEPROP 0 LASTPIN (-2800 950) $PN P5_5
J 0
(-2790 960);
DISPLAY 0.680851 (-2790 960);
PAINT MONO (-2790 960);
FORCEPROP 0 LASTPIN (-2800 900) $PN P5_6
J 0
(-2790 910);
DISPLAY 0.680851 (-2790 910);
PAINT MONO (-2790 910);
FORCEPROP 0 LASTPIN (-2800 850) $PN P5_7
J 0
(-2790 860);
DISPLAY 0.680851 (-2790 860);
PAINT MONO (-2790 860);
FORCEPROP 0 LASTPIN (-2800 800) $PN P5_8
J 0
(-2790 810);
DISPLAY 0.680851 (-2790 810);
PAINT MONO (-2790 810);
FORCEPROP 0 LASTPIN (-2800 650) $PN P6_1
J 0
(-2790 660);
DISPLAY 0.680851 (-2790 660);
PAINT MONO (-2790 660);
FORCEPROP 0 LASTPIN (-2800 600) $PN P6_2
J 0
(-2790 610);
DISPLAY 0.680851 (-2790 610);
PAINT MONO (-2790 610);
FORCEPROP 0 LASTPIN (-2800 550) $PN P6_3
J 0
(-2790 560);
DISPLAY 0.680851 (-2790 560);
PAINT MONO (-2790 560);
FORCEPROP 0 LASTPIN (-2800 500) $PN P6_4
J 0
(-2790 510);
DISPLAY 0.680851 (-2790 510);
PAINT MONO (-2790 510);
FORCEPROP 0 LASTPIN (-2800 450) $PN P6_5
J 0
(-2790 460);
DISPLAY 0.680851 (-2790 460);
PAINT MONO (-2790 460);
FORCEPROP 0 LASTPIN (-2800 400) $PN P6_6
J 0
(-2790 410);
DISPLAY 0.680851 (-2790 410);
PAINT MONO (-2790 410);
FORCEPROP 0 LASTPIN (-2800 350) $PN P6_7
J 0
(-2790 360);
DISPLAY 0.680851 (-2790 360);
PAINT MONO (-2790 360);
FORCEPROP 0 LASTPIN (-2800 300) $PN P6_8
J 0
(-2790 310);
DISPLAY 0.680851 (-2790 310);
PAINT MONO (-2790 310);
FORCEPROP 1 LAST CDS_LMAN_SYM_OUTLINE -250,1000,250,-1000
J 0
(-3200 1150);
DISPLAY 0.468085 (-3200 1150);
PAINT GREEN (-3200 1150);
DISPLAY INVISIBLE (-3200 1150);
FORCEPROP 1 LAST NEEDS_NO_SIZE TRUE
J 0
(-3200 1150);
DISPLAY 0.723404 (-3200 1150);
PAINT GREEN (-3200 1150);
DISPLAY INVISIBLE (-3200 1150);
FORCEPROP 2 LAST CDS_LIB pure_quanta
J 0
(-3200 1150);
DISPLAY INVISIBLE (-3200 1150);
FORCEPROP 1 LAST PATH I12
J 0
(-3200 1150);
DISPLAY 0.723404 (-3200 1150);
PAINT GREEN (-3200 1150);
DISPLAY INVISIBLE (-3200 1150);
FORCEPROP 0 LAST $SEC 1
J 0
(-3450 2425);
DISPLAY 0.680851 (-3450 2425);
PAINT MONO (-3450 2425);
DISPLAY INVISIBLE (-3450 2425);
FORCEPROP 0 LAST CDS_SEC 1
J 0
(-3450 2425);
DISPLAY 1.021277 (-3450 2425);
DISPLAY INVISIBLE (-3450 2425);
FORCEADD UNIVERSAL_GND..1
(-2975 -2425);
FORCEPROP 3 LASTPIN (-2975 -2375) SIG_NAME GND\g
J 0
(-2965 -2365);
DISPLAY 0.659574 (-2965 -2365);
PAINT MONO (-2965 -2365);
DISPLAY INVISIBLE (-2965 -2365);
FORCEPROP 1 LAST HDL_POWER GND
J 1
(-2950 -2500);
DISPLAY 0.872340 (-2950 -2500);
PAINT GREEN (-2950 -2500);
DISPLAY INVISIBLE (-2950 -2500);
FORCEPROP 2 LAST CDS_LIB logical_power
J 0
(-2975 -2425);
DISPLAY INVISIBLE (-2975 -2425);
FORCEPROP 1 LAST PATH I13
J 0
(-2900 -2425);
DISPLAY 0.872340 (-2900 -2425);
PAINT AQUA (-2900 -2425);
DISPLAY INVISIBLE (-2900 -2425);
FORCEADD Q_RES..1
(-2575 -2650);
FORCEPROP 1 LAST PART_NUMBER CS00002JB13
J 0
(-2675 -2700);
DISPLAY 0.404255 (-2675 -2700);
DISPLAY INVISIBLE (-2675 -2700);
FORCEPROP 1 LAST PACK_TYPE 0402LF
J 0
(-2675 -2750);
DISPLAY 0.404255 (-2675 -2750);
FORCEPROP 1 LAST VALUE 0
J 2
(-2425 -2650);
DISPLAY 0.510638 (-2425 -2650);
FORCEPROP 1 LAST WATTAGE 1/16W
J 2
(-2450 -2750);
DISPLAY 0.404255 (-2450 -2750);
FORCEPROP 1 LAST MATERIAL EMPTY
J 0
(-2275 -2650);
DISPLAY 0.510638 (-2275 -2650);
PAINT RED (-2275 -2650);
FORCEPROP 1 LAST TOLERANCE 5%
J 0
(-2350 -2650);
DISPLAY 0.510638 (-2350 -2650);
FORCEPROP 1 LAST $LOCATION R2801
J 0
(-2750 -2650);
DISPLAY 0.638298 (-2750 -2650);
FORCEPROP 1 LASTPIN (-2675 -2650) $PN 1
J 0
(-2663 -2638);
DISPLAY 0.787234 (-2663 -2638);
PAINT MONO (-2663 -2638);
FORCEPROP 1 LASTPIN (-2475 -2650) $PN 2
J 0
(-2513 -2638);
DISPLAY 0.787234 (-2513 -2638);
PAINT MONO (-2513 -2638);
FORCEPROP 2 LAST CDS_LIB pure_quanta
J 0
(-2575 -2650);
DISPLAY INVISIBLE (-2575 -2650);
FORCEPROP 1 LAST PATH I14
J 0
(-2625 -2500);
DISPLAY 0.978723 (-2625 -2500);
PAINT WHITE (-2625 -2500);
DISPLAY INVISIBLE (-2625 -2500);
FORCEPROP 2 LAST CDS_LOCATION R2801
J 0
(-2625 -2450);
DISPLAY 1.021277 (-2625 -2450);
DISPLAY INVISIBLE (-2625 -2450);
FORCEPROP 2 LAST $SEC 1
J 0
(-2625 -2450);
DISPLAY 0.680851 (-2625 -2450);
PAINT MONO (-2625 -2450);
DISPLAY INVISIBLE (-2625 -2450);
FORCEPROP 2 LAST CDS_SEC 1
J 0
(-2625 -2450);
DISPLAY 1.021277 (-2625 -2450);
DISPLAY INVISIBLE (-2625 -2450);
FORCEADD Q_RES..1
(-2575 -2575);
FORCEPROP 1 LAST PART_NUMBER CS00002JB13
J 0
(-2675 -2625);
DISPLAY 0.404255 (-2675 -2625);
DISPLAY INVISIBLE (-2675 -2625);
FORCEPROP 1 LAST VALUE 0
J 2
(-2425 -2575);
DISPLAY 0.510638 (-2425 -2575);
FORCEPROP 1 LAST MATERIAL EMPTY
J 0
(-2275 -2575);
DISPLAY 0.510638 (-2275 -2575);
PAINT RED (-2275 -2575);
FORCEPROP 1 LAST $LOCATION R2800
J 0
(-2750 -2575);
DISPLAY 0.638298 (-2750 -2575);
FORCEPROP 1 LASTPIN (-2675 -2575) $PN 1
J 0
(-2663 -2563);
DISPLAY 0.787234 (-2663 -2563);
PAINT MONO (-2663 -2563);
FORCEPROP 1 LASTPIN (-2475 -2575) $PN 2
J 0
(-2513 -2563);
DISPLAY 0.787234 (-2513 -2563);
PAINT MONO (-2513 -2563);
FORCEPROP 2 LAST CDS_LIB pure_quanta
J 0
(-2575 -2575);
DISPLAY INVISIBLE (-2575 -2575);
FORCEPROP 1 LAST PACK_TYPE 0402LF
J 0
(-2675 -2675);
DISPLAY 0.404255 (-2675 -2675);
DISPLAY INVISIBLE (-2675 -2675);
FORCEPROP 1 LAST TOLERANCE 5%
J 0
(-2350 -2575);
DISPLAY 0.510638 (-2350 -2575);
DISPLAY INVISIBLE (-2350 -2575);
FORCEPROP 1 LAST WATTAGE 1/16W
J 2
(-2450 -2675);
DISPLAY 0.404255 (-2450 -2675);
DISPLAY INVISIBLE (-2450 -2675);
FORCEPROP 1 LAST PATH I15
J 0
(-2625 -2425);
DISPLAY 0.978723 (-2625 -2425);
PAINT WHITE (-2625 -2425);
DISPLAY INVISIBLE (-2625 -2425);
FORCEPROP 0 LAST CDS_LOCATION R2800
J 0
(-2450 -2475);
DISPLAY 1.021277 (-2450 -2475);
DISPLAY INVISIBLE (-2450 -2475);
FORCEPROP 0 LAST $SEC 1
J 0
(-2450 -2475);
DISPLAY 0.680851 (-2450 -2475);
PAINT MONO (-2450 -2475);
DISPLAY INVISIBLE (-2450 -2475);
FORCEPROP 0 LAST CDS_SEC 1
J 0
(-2450 -2475);
DISPLAY 1.021277 (-2450 -2475);
DISPLAY INVISIBLE (-2450 -2475);
FORCEADD LTC4307CMS8..1
(-2550 -2175);
FORCEPROP 1 LAST PART_NUMBER AL004307000
J 0
(-2800 -1915);
DISPLAY 0.723404 (-2800 -1915);
PAINT GREEN (-2800 -1915);
DISPLAY INVISIBLE (-2800 -1915);
FORCEPROP 2 LAST PART_TYPE SMLF
J 0
(-2800 -1775);
DISPLAY 1.021277 (-2800 -1775);
FORCEPROP 2 LAST VALUE LTC4307CMS8
J 0
(-2800 -1825);
DISPLAY 1.021277 (-2800 -1825);
FORCEPROP 1 LAST MATERIAL IC
J 0
(-2800 -1965);
DISPLAY 0.723404 (-2800 -1965);
PAINT GREEN (-2800 -1965);
FORCEPROP 1 LAST $LOCATION U192
J 0
(-2800 -1870);
DISPLAY 0.723404 (-2800 -1870);
PAINT GREEN (-2800 -1870);
FORCEPROP 2 LASTPIN (-2950 -2025) $PN 1
J 2
(-2960 -2015);
DISPLAY 0.680851 (-2960 -2015);
PAINT MONO (-2960 -2015);
FORCEPROP 2 LASTPIN (-2950 -2325) $PN 4
J 2
(-2960 -2315);
DISPLAY 0.680851 (-2960 -2315);
PAINT MONO (-2960 -2315);
FORCEPROP 2 LASTPIN (-2150 -2325) $PN 5
J 0
(-2140 -2315);
DISPLAY 0.680851 (-2140 -2315);
PAINT MONO (-2140 -2315);
FORCEPROP 2 LASTPIN (-2950 -2125) $PN 3
J 2
(-2960 -2115);
DISPLAY 0.680851 (-2960 -2115);
PAINT MONO (-2960 -2115);
FORCEPROP 2 LASTPIN (-2150 -2125) $PN 2
J 0
(-2140 -2115);
DISPLAY 0.680851 (-2140 -2115);
PAINT MONO (-2140 -2115);
FORCEPROP 2 LASTPIN (-2950 -2225) $PN 6
J 2
(-2960 -2215);
DISPLAY 0.680851 (-2960 -2215);
PAINT MONO (-2960 -2215);
FORCEPROP 2 LASTPIN (-2150 -2225) $PN 7
J 0
(-2140 -2215);
DISPLAY 0.680851 (-2140 -2215);
PAINT MONO (-2140 -2215);
FORCEPROP 2 LASTPIN (-2150 -2025) $PN 8
J 0
(-2140 -2015);
DISPLAY 0.680851 (-2140 -2015);
PAINT MONO (-2140 -2015);
FORCEPROP 2 LAST CDS_LIB pure_quanta
J 0
(-2550 -2175);
DISPLAY INVISIBLE (-2550 -2175);
FORCEPROP 1 LAST NEEDS_NO_SIZE TRUE
J 0
(-2550 -2175);
DISPLAY 0.468085 (-2550 -2175);
PAINT GREEN (-2550 -2175);
DISPLAY INVISIBLE (-2550 -2175);
FORCEPROP 1 LAST PATH I16
J 0
(-2325 -1970);
DISPLAY 0.723404 (-2325 -1970);
PAINT GREEN (-2325 -1970);
DISPLAY INVISIBLE (-2325 -1970);
FORCEPROP 2 LAST CDS_LOCATION U192
J 0
(-2800 -1725);
DISPLAY 1.021277 (-2800 -1725);
DISPLAY INVISIBLE (-2800 -1725);
FORCEPROP 2 LAST $SEC 1
J 0
(-2800 -1725);
DISPLAY 0.680851 (-2800 -1725);
PAINT MONO (-2800 -1725);
DISPLAY INVISIBLE (-2800 -1725);
FORCEPROP 2 LAST CDS_SEC 1
J 0
(-2800 -1725);
DISPLAY 1.021277 (-2800 -1725);
DISPLAY INVISIBLE (-2800 -1725);
FORCEADD UNIVERSAL_GND..1
(-1700 -1850);
FORCEPROP 3 LASTPIN (-1700 -1800) SIG_NAME GND\g
J 0
(-1690 -1790);
DISPLAY 0.659574 (-1690 -1790);
PAINT MONO (-1690 -1790);
DISPLAY INVISIBLE (-1690 -1790);
FORCEPROP 2 LAST CDS_LIB logical_power
J 0
(-1700 -1850);
DISPLAY INVISIBLE (-1700 -1850);
FORCEPROP 1 LAST HDL_POWER GND
J 1
(-1675 -1925);
DISPLAY 0.872340 (-1675 -1925);
PAINT GREEN (-1675 -1925);
DISPLAY INVISIBLE (-1675 -1925);
FORCEPROP 1 LAST PATH I17
J 0
(-1625 -1850);
DISPLAY 0.872340 (-1625 -1850);
PAINT AQUA (-1625 -1850);
DISPLAY INVISIBLE (-1625 -1850);
FORCEADD UNIVERSAL_POWER..1
(-2050 -1325);
FORCEPROP 3 LASTPIN (-2050 -1375) SIG_NAME P3V3_AUX\g
J 0
(-2040 -1365);
DISPLAY 0.659574 (-2040 -1365);
PAINT MONO (-2040 -1365);
DISPLAY INVISIBLE (-2040 -1365);
FORCEPROP 1 LAST HDL_POWER P3V3_AUX
J 1
(-2050 -1275);
DISPLAY 0.872340 (-2050 -1275);
PAINT GREEN (-2050 -1275);
FORCEPROP 2 LAST CDS_LIB logical_power
J 0
(-2050 -1325);
PAINT MONO (-2050 -1325);
DISPLAY INVISIBLE (-2050 -1325);
FORCEPROP 1 LAST PATH I18
J 0
(-2000 -1300);
DISPLAY 0.872340 (-2000 -1300);
PAINT AQUA (-2000 -1300);
DISPLAY INVISIBLE (-2000 -1300);
FORCEADD Q_CAP..1
R 2
(-1700 -1600);
FORCEPROP 1 LAST PART_NUMBER CH4104K1B00
J 2
(-1750 -1750);
DISPLAY 0.510638 (-1750 -1750);
DISPLAY INVISIBLE (-1750 -1750);
FORCEPROP 1 LAST PACK_TYPE 0402
J 2
(-1750 -1800);
DISPLAY 0.510638 (-1750 -1800);
FORCEPROP 1 LAST TOLERANCE 10%
J 2
(-1750 -1650);
DISPLAY 0.510638 (-1750 -1650);
FORCEPROP 1 LAST VOLTAGE 25V
J 2
(-1750 -1600);
DISPLAY 0.510638 (-1750 -1600);
FORCEPROP 1 LAST MATERIAL X7R
J 2
(-1750 -1700);
DISPLAY 0.510638 (-1750 -1700);
FORCEPROP 1 LAST VALUE 0.1UF
J 2
(-1750 -1550);
DISPLAY 0.510638 (-1750 -1550);
FORCEPROP 1 LAST $LOCATION C1751
J 2
(-1750 -1500);
DISPLAY 0.638298 (-1750 -1500);
FORCEPROP 1 LASTPIN (-1700 -1500) $PN 1
J 2
(-1710 -1520);
DISPLAY 0.787234 (-1710 -1520);
FORCEPROP 1 LASTPIN (-1700 -1700) $PN 2
J 2
(-1710 -1720);
DISPLAY 0.787234 (-1710 -1720);
FORCEPROP 2 LAST CDS_LIB pure_quanta
J 2
(-1700 -1600);
PAINT MONO (-1700 -1600);
DISPLAY INVISIBLE (-1700 -1600);
FORCEPROP 1 LAST PATH I19
J 2
(-1750 -1450);
DISPLAY 0.978723 (-1750 -1450);
PAINT WHITE (-1750 -1450);
DISPLAY INVISIBLE (-1750 -1450);
FORCEPROP 2 LAST CDS_LOCATION C1751
J 0
(-1750 -1400);
DISPLAY 1.021277 (-1750 -1400);
DISPLAY INVISIBLE (-1750 -1400);
FORCEPROP 2 LAST $SEC 1
J 0
(-1750 -1400);
DISPLAY 0.680851 (-1750 -1400);
PAINT MONO (-1750 -1400);
DISPLAY INVISIBLE (-1750 -1400);
FORCEPROP 2 LAST CDS_SEC 1
J 0
(-1750 -1400);
DISPLAY 1.021277 (-1750 -1400);
DISPLAY INVISIBLE (-1750 -1400);
FORCEADD UNIVERSAL_GND..1
(-5725 -2625);
FORCEPROP 3 LASTPIN (-5725 -2575) SIG_NAME GND\g
J 0
(-5715 -2565);
DISPLAY 0.659574 (-5715 -2565);
PAINT MONO (-5715 -2565);
DISPLAY INVISIBLE (-5715 -2565);
FORCEPROP 2 LAST CDS_LIB logical_power
J 0
(-5725 -2625);
DISPLAY INVISIBLE (-5725 -2625);
FORCEPROP 1 LAST HDL_POWER GND
J 1
(-5700 -2700);
DISPLAY 0.872340 (-5700 -2700);
PAINT GREEN (-5700 -2700);
DISPLAY INVISIBLE (-5700 -2700);
FORCEPROP 1 LAST PATH I2
J 0
(-5650 -2625);
DISPLAY 0.872340 (-5650 -2625);
PAINT AQUA (-5650 -2625);
DISPLAY INVISIBLE (-5650 -2625);
FORCEADD Q_RES..1
(-525 -2225);
FORCEPROP 1 LAST PART_NUMBER CS03322FB03
J 0
(-650 -2175);
DISPLAY 0.404255 (-650 -2175);
DISPLAY INVISIBLE (-650 -2175);
FORCEPROP 1 LAST MATERIAL CHIP
J 0
(-225 -2225);
DISPLAY 0.510638 (-225 -2225);
FORCEPROP 1 LAST VALUE 33.2
J 2
(-325 -2225);
DISPLAY 0.510638 (-325 -2225);
FORCEPROP 1 LAST TOLERANCE 1%
J 0
(-300 -2225);
DISPLAY 0.510638 (-300 -2225);
FORCEPROP 1 LAST $LOCATION R2812
J 0
(-750 -2225);
DISPLAY 0.638298 (-750 -2225);
FORCEPROP 1 LASTPIN (-625 -2225) $PN 1
J 0
(-613 -2213);
DISPLAY 0.787234 (-613 -2213);
PAINT MONO (-613 -2213);
FORCEPROP 1 LASTPIN (-425 -2225) $PN 2
J 0
(-463 -2213);
DISPLAY 0.787234 (-463 -2213);
PAINT MONO (-463 -2213);
FORCEPROP 2 LAST CDS_LIB pure_quanta
J 0
(-525 -2225);
DISPLAY INVISIBLE (-525 -2225);
FORCEPROP 1 LAST PACK_TYPE 0402LF
J 0
(-650 -2125);
DISPLAY 0.404255 (-650 -2125);
DISPLAY INVISIBLE (-650 -2125);
FORCEPROP 1 LAST WATTAGE 1/16W
J 2
(-425 -2125);
DISPLAY 0.404255 (-425 -2125);
DISPLAY INVISIBLE (-425 -2125);
FORCEPROP 1 LAST PATH I20
J 0
(-575 -2075);
DISPLAY 0.978723 (-575 -2075);
PAINT WHITE (-575 -2075);
DISPLAY INVISIBLE (-575 -2075);
FORCEPROP 0 LAST CDS_LOCATION R2812
J 0
(-750 -2175);
DISPLAY 1.021277 (-750 -2175);
DISPLAY INVISIBLE (-750 -2175);
FORCEPROP 0 LAST $SEC 1
J 0
(-750 -2175);
DISPLAY 0.680851 (-750 -2175);
PAINT MONO (-750 -2175);
DISPLAY INVISIBLE (-750 -2175);
FORCEPROP 0 LAST CDS_SEC 1
J 0
(-750 -2175);
DISPLAY 1.021277 (-750 -2175);
DISPLAY INVISIBLE (-750 -2175);
FORCEADD Q_RES..1
(-525 -2125);
FORCEPROP 1 LAST PART_NUMBER CS03322FB03
J 0
(-650 -2075);
DISPLAY 0.404255 (-650 -2075);
DISPLAY INVISIBLE (-650 -2075);
FORCEPROP 1 LAST MATERIAL CHIP
J 0
(-225 -2125);
DISPLAY 0.510638 (-225 -2125);
FORCEPROP 1 LAST TOLERANCE 1%
J 0
(-300 -2125);
DISPLAY 0.510638 (-300 -2125);
FORCEPROP 1 LAST VALUE 33.2
J 2
(-325 -2125);
DISPLAY 0.510638 (-325 -2125);
FORCEPROP 1 LAST $LOCATION R2811
J 0
(-750 -2125);
DISPLAY 0.638298 (-750 -2125);
FORCEPROP 1 LASTPIN (-625 -2125) $PN 1
J 0
(-613 -2113);
DISPLAY 0.787234 (-613 -2113);
PAINT MONO (-613 -2113);
FORCEPROP 1 LASTPIN (-425 -2125) $PN 2
J 0
(-463 -2113);
DISPLAY 0.787234 (-463 -2113);
PAINT MONO (-463 -2113);
FORCEPROP 1 LAST PACK_TYPE 0402LF
J 0
(-650 -2025);
DISPLAY 0.404255 (-650 -2025);
DISPLAY INVISIBLE (-650 -2025);
FORCEPROP 1 LAST WATTAGE 1/16W
J 2
(-425 -2025);
DISPLAY 0.404255 (-425 -2025);
DISPLAY INVISIBLE (-425 -2025);
FORCEPROP 2 LAST CDS_LIB pure_quanta
J 0
(-525 -2125);
DISPLAY INVISIBLE (-525 -2125);
FORCEPROP 1 LAST PATH I21
J 0
(-575 -1975);
DISPLAY 0.978723 (-575 -1975);
PAINT WHITE (-575 -1975);
DISPLAY INVISIBLE (-575 -1975);
FORCEPROP 0 LAST CDS_LOCATION R2811
J 0
(-750 -2075);
DISPLAY 1.021277 (-750 -2075);
DISPLAY INVISIBLE (-750 -2075);
FORCEPROP 0 LAST $SEC 1
J 0
(-750 -2075);
DISPLAY 0.680851 (-750 -2075);
PAINT MONO (-750 -2075);
DISPLAY INVISIBLE (-750 -2075);
FORCEPROP 0 LAST CDS_SEC 1
J 0
(-750 -2075);
DISPLAY 1.021277 (-750 -2075);
DISPLAY INVISIBLE (-750 -2075);
FORCEADD Q_RES..2
(-1250 -1675);
FORCEPROP 1 LAST PART_NUMBER CS24702JB10
J 0
(-1210 -1850);
DISPLAY 0.638298 (-1210 -1850);
DISPLAY INVISIBLE (-1210 -1850);
FORCEPROP 1 LAST WATTAGE 1/16W
J 0
(-1210 -1700);
DISPLAY 0.638298 (-1210 -1700);
FORCEPROP 1 LAST TOLERANCE 5%
J 0
(-1205 -1650);
DISPLAY 0.638298 (-1205 -1650);
FORCEPROP 1 LAST VALUE 4.7K
J 0
(-1205 -1600);
DISPLAY 0.638298 (-1205 -1600);
FORCEPROP 1 LAST MATERIAL EMPTY
J 0
(-1210 -1750);
DISPLAY 0.638298 (-1210 -1750);
FORCEPROP 1 LAST PACK_TYPE 0402LF
J 0
(-1210 -1800);
DISPLAY 0.638298 (-1210 -1800);
FORCEPROP 1 LAST $LOCATION R2805
J 0
(-1205 -1550);
DISPLAY 0.638298 (-1205 -1550);
FORCEPROP 1 LASTPIN (-1250 -1575) $PN 1
J 0
(-1245 -1613);
DISPLAY 0.787234 (-1245 -1613);
FORCEPROP 1 LASTPIN (-1250 -1775) $PN 2
J 0
(-1245 -1765);
DISPLAY 0.787234 (-1245 -1765);
FORCEPROP 2 LAST CDS_LIB pure_quanta
J 0
(-1250 -1675);
PAINT MONO (-1250 -1675);
DISPLAY INVISIBLE (-1250 -1675);
FORCEPROP 1 LAST PATH I22
J 0
(-1200 -1500);
DISPLAY 0.978723 (-1200 -1500);
PAINT WHITE (-1200 -1500);
DISPLAY INVISIBLE (-1200 -1500);
FORCEPROP 2 LAST CDS_LOCATION R2805
J 0
(-1200 -1450);
DISPLAY 1.021277 (-1200 -1450);
DISPLAY INVISIBLE (-1200 -1450);
FORCEPROP 2 LAST $SEC 1
J 0
(-1200 -1450);
DISPLAY 0.680851 (-1200 -1450);
PAINT MONO (-1200 -1450);
DISPLAY INVISIBLE (-1200 -1450);
FORCEPROP 2 LAST CDS_SEC 1
J 0
(-1200 -1450);
DISPLAY 1.021277 (-1200 -1450);
DISPLAY INVISIBLE (-1200 -1450);
FORCEADD UNIVERSAL_POWER..1
(-1250 -1375);
FORCEPROP 3 LASTPIN (-1250 -1425) SIG_NAME P3V3_AUX\g
J 0
(-1240 -1415);
DISPLAY 0.659574 (-1240 -1415);
PAINT MONO (-1240 -1415);
DISPLAY INVISIBLE (-1240 -1415);
FORCEPROP 1 LAST HDL_POWER P3V3_AUX
J 1
(-1250 -1325);
DISPLAY 0.872340 (-1250 -1325);
PAINT GREEN (-1250 -1325);
FORCEPROP 2 LAST CDS_LIB logical_power
J 0
(-1250 -1375);
PAINT MONO (-1250 -1375);
DISPLAY INVISIBLE (-1250 -1375);
FORCEPROP 1 LAST PATH I23
J 0
(-1200 -1350);
DISPLAY 0.872340 (-1200 -1350);
PAINT AQUA (-1200 -1350);
DISPLAY INVISIBLE (-1200 -1350);
FORCEADD Q_RES..2
(-1000 -1700);
FORCEPROP 1 LAST PART_NUMBER CS24702JB10
J 0
(-960 -1875);
DISPLAY 0.638298 (-960 -1875);
DISPLAY INVISIBLE (-960 -1875);
FORCEPROP 1 LAST PACK_TYPE 0402LF
J 0
(-960 -1825);
DISPLAY 0.638298 (-960 -1825);
FORCEPROP 1 LAST WATTAGE 1/16W
J 0
(-960 -1725);
DISPLAY 0.638298 (-960 -1725);
FORCEPROP 1 LAST TOLERANCE 5%
J 0
(-955 -1675);
DISPLAY 0.638298 (-955 -1675);
FORCEPROP 1 LAST MATERIAL EMPTY
J 0
(-960 -1775);
DISPLAY 0.638298 (-960 -1775);
FORCEPROP 1 LAST VALUE 4.7K
J 0
(-955 -1625);
DISPLAY 0.638298 (-955 -1625);
FORCEPROP 1 LAST $LOCATION R2807
J 0
(-955 -1575);
DISPLAY 0.638298 (-955 -1575);
FORCEPROP 1 LASTPIN (-1000 -1600) $PN 1
J 0
(-995 -1638);
DISPLAY 0.787234 (-995 -1638);
FORCEPROP 1 LASTPIN (-1000 -1800) $PN 2
J 0
(-995 -1790);
DISPLAY 0.787234 (-995 -1790);
FORCEPROP 2 LAST CDS_LIB pure_quanta
J 0
(-1000 -1700);
PAINT MONO (-1000 -1700);
DISPLAY INVISIBLE (-1000 -1700);
FORCEPROP 1 LAST PATH I24
J 0
(-950 -1525);
DISPLAY 0.978723 (-950 -1525);
PAINT WHITE (-950 -1525);
DISPLAY INVISIBLE (-950 -1525);
FORCEPROP 2 LAST CDS_LOCATION R2807
J 0
(-950 -1475);
DISPLAY 1.021277 (-950 -1475);
DISPLAY INVISIBLE (-950 -1475);
FORCEPROP 2 LAST $SEC 1
J 0
(-950 -1475);
DISPLAY 0.680851 (-950 -1475);
PAINT MONO (-950 -1475);
DISPLAY INVISIBLE (-950 -1475);
FORCEPROP 2 LAST CDS_SEC 1
J 0
(-950 -1475);
DISPLAY 1.021277 (-950 -1475);
DISPLAY INVISIBLE (-950 -1475);
FORCEADD OFFPAGE..5
(-500 550);
FORCEPROP 2 LAST $XR0 245 
J 0
(-755 550);
DISPLAY 0.638298 (-755 550);
PAINT MONO (-755 550);
FORCEPROP 2 LAST CDS_LIB standard
J 0
(-500 550);
DISPLAY INVISIBLE (-500 550);
FORCEPROP 1 LAST OFFPAGE TRUE
J 0
(-175 425);
DISPLAY 0.872340 (-175 425);
DISPLAY INVISIBLE (-175 425);
FORCEPROP 1 LAST COMMENT_BODY TRUE
J 0
(-400 475);
DISPLAY 0.872340 (-400 475);
PAINT GREEN (-400 475);
DISPLAY INVISIBLE (-400 475);
FORCEPROP 2 LAST PATH I25
J 0
(-750 600);
DISPLAY 1.021277 (-750 600);
DISPLAY INVISIBLE (-750 600);
FORCEADD OFFPAGE..5
(-500 725);
FORCEPROP 2 LAST $XR0 245 
J 0
(-755 725);
DISPLAY 0.638298 (-755 725);
PAINT MONO (-755 725);
FORCEPROP 1 LAST COMMENT_BODY TRUE
J 0
(-400 650);
DISPLAY 0.872340 (-400 650);
PAINT GREEN (-400 650);
DISPLAY INVISIBLE (-400 650);
FORCEPROP 1 LAST OFFPAGE TRUE
J 0
(-175 600);
DISPLAY 0.872340 (-175 600);
DISPLAY INVISIBLE (-175 600);
FORCEPROP 2 LAST CDS_LIB standard
J 0
(-500 725);
DISPLAY INVISIBLE (-500 725);
FORCEPROP 2 LAST PATH I26
J 0
(-750 775);
DISPLAY 1.021277 (-750 775);
DISPLAY INVISIBLE (-750 775);
FORCEADD OFFPAGE..5
(-500 875);
FORCEPROP 2 LAST $XR0 245 
J 0
(-755 875);
DISPLAY 0.638298 (-755 875);
PAINT MONO (-755 875);
FORCEPROP 1 LAST OFFPAGE TRUE
J 0
(-175 750);
DISPLAY 0.872340 (-175 750);
DISPLAY INVISIBLE (-175 750);
FORCEPROP 1 LAST COMMENT_BODY TRUE
J 0
(-400 800);
DISPLAY 0.872340 (-400 800);
PAINT GREEN (-400 800);
DISPLAY INVISIBLE (-400 800);
FORCEPROP 2 LAST CDS_LIB standard
J 0
(-500 875);
DISPLAY INVISIBLE (-500 875);
FORCEPROP 2 LAST PATH I27
J 0
(-750 925);
DISPLAY 1.021277 (-750 925);
DISPLAY INVISIBLE (-750 925);
FORCEADD OFFPAGE..5
(-500 1025);
FORCEPROP 2 LAST $XR0 245 
J 0
(-755 1025);
DISPLAY 0.638298 (-755 1025);
PAINT MONO (-755 1025);
FORCEPROP 2 LAST CDS_LIB standard
J 0
(-500 1025);
DISPLAY INVISIBLE (-500 1025);
FORCEPROP 1 LAST COMMENT_BODY TRUE
J 0
(-400 950);
DISPLAY 0.872340 (-400 950);
PAINT GREEN (-400 950);
DISPLAY INVISIBLE (-400 950);
FORCEPROP 1 LAST OFFPAGE TRUE
J 0
(-175 900);
DISPLAY 0.872340 (-175 900);
DISPLAY INVISIBLE (-175 900);
FORCEPROP 2 LAST PATH I28
J 0
(-750 1075);
DISPLAY 1.021277 (-750 1075);
DISPLAY INVISIBLE (-750 1075);
FORCEADD OFFPAGE..5
(-500 1175);
FORCEPROP 2 LAST $XR0 245 
J 0
(-755 1175);
DISPLAY 0.638298 (-755 1175);
PAINT MONO (-755 1175);
FORCEPROP 2 LAST $XR1 301 
J 0
(-755 1139);
DISPLAY 0.638298 (-755 1139);
PAINT MONO (-755 1139);
FORCEPROP 2 LAST CDS_LIB standard
J 0
(-500 1175);
DISPLAY INVISIBLE (-500 1175);
FORCEPROP 1 LAST OFFPAGE TRUE
J 0
(-175 1050);
DISPLAY 0.872340 (-175 1050);
DISPLAY INVISIBLE (-175 1050);
FORCEPROP 1 LAST COMMENT_BODY TRUE
J 0
(-400 1100);
DISPLAY 0.872340 (-400 1100);
PAINT GREEN (-400 1100);
DISPLAY INVISIBLE (-400 1100);
FORCEPROP 2 LAST PATH I29
J 0
(-750 1225);
DISPLAY 1.021277 (-750 1225);
DISPLAY INVISIBLE (-750 1225);
FORCEADD Q_RES..2
(-5725 -2250);
FORCEPROP 1 LAST PART_NUMBER CS41002FB09
J 0
(-5685 -2375);
DISPLAY 0.510638 (-5685 -2375);
DISPLAY INVISIBLE (-5685 -2375);
FORCEPROP 1 LAST WATTAGE 1/16W
J 0
(-5685 -2275);
DISPLAY 0.510638 (-5685 -2275);
FORCEPROP 1 LAST MATERIAL CHIP
J 0
(-5685 -2325);
DISPLAY 0.510638 (-5685 -2325);
FORCEPROP 1 LAST VALUE 100K
J 0
(-5680 -2175);
DISPLAY 0.510638 (-5680 -2175);
FORCEPROP 1 LAST TOLERANCE 1%
J 0
(-5680 -2225);
DISPLAY 0.510638 (-5680 -2225);
FORCEPROP 1 LAST PACK_TYPE 0402LF
J 0
(-5685 -2425);
DISPLAY 0.510638 (-5685 -2425);
FORCEPROP 1 LAST $LOCATION R4769
J 0
(-5680 -2125);
DISPLAY 0.978723 (-5680 -2125);
FORCEPROP 1 LASTPIN (-5725 -2150) $PN 1
J 0
(-5720 -2188);
DISPLAY 0.787234 (-5720 -2188);
PAINT MONO (-5720 -2188);
FORCEPROP 1 LASTPIN (-5725 -2350) $PN 2
J 0
(-5720 -2340);
DISPLAY 0.787234 (-5720 -2340);
PAINT MONO (-5720 -2340);
FORCEPROP 2 LAST CDS_LIB pure_quanta
J 0
(-5725 -2250);
DISPLAY INVISIBLE (-5725 -2250);
FORCEPROP 1 LAST PATH I3
J 0
(-5675 -2075);
DISPLAY 0.978723 (-5675 -2075);
PAINT WHITE (-5675 -2075);
DISPLAY INVISIBLE (-5675 -2075);
FORCEPROP 0 LAST CDS_LOCATION R4769
J 0
(-5675 -2075);
DISPLAY 1.021277 (-5675 -2075);
DISPLAY INVISIBLE (-5675 -2075);
FORCEPROP 0 LAST $SEC 1
J 0
(-5675 -2075);
DISPLAY 0.680851 (-5675 -2075);
PAINT MONO (-5675 -2075);
DISPLAY INVISIBLE (-5675 -2075);
FORCEPROP 0 LAST CDS_SEC 1
J 0
(-5675 -2075);
DISPLAY 1.021277 (-5675 -2075);
DISPLAY INVISIBLE (-5675 -2075);
FORCEADD OFFPAGE..1
(-6500 1900);
FORCEPROP 2 LAST $XR0 215 
J 0
(-6782 1900);
DISPLAY 0.638298 (-6782 1900);
PAINT MONO (-6782 1900);
FORCEPROP 2 LAST $XR1 154 
J 0
(-6902 1900);
DISPLAY 0.638298 (-6902 1900);
PAINT MONO (-6902 1900);
FORCEPROP 2 LAST $XR2 161 
J 0
(-7022 1900);
DISPLAY 0.638298 (-7022 1900);
PAINT MONO (-7022 1900);
FORCEPROP 2 LAST $XR3 191 
J 0
(-7142 1900);
DISPLAY 0.638298 (-7142 1900);
PAINT MONO (-7142 1900);
FORCEPROP 2 LAST $XR4 227 
J 0
(-7262 1900);
DISPLAY 0.638298 (-7262 1900);
PAINT MONO (-7262 1900);
FORCEPROP 2 LAST $XR5 231 
J 0
(-7382 1900);
DISPLAY 0.638298 (-7382 1900);
PAINT MONO (-7382 1900);
FORCEPROP 2 LAST $XR6 233 
J 0
(-7502 1900);
DISPLAY 0.638298 (-7502 1900);
PAINT MONO (-7502 1900);
FORCEPROP 2 LAST $XR7 236 
J 0
(-7622 1900);
DISPLAY 0.638298 (-7622 1900);
PAINT MONO (-7622 1900);
FORCEPROP 2 LAST CDS_LIB standard
J 0
(-6500 1900);
DISPLAY INVISIBLE (-6500 1900);
FORCEPROP 1 LAST COMMENT_BODY TRUE
J 0
(-6375 1800);
DISPLAY 0.872340 (-6375 1800);
PAINT GREEN (-6375 1800);
DISPLAY INVISIBLE (-6375 1800);
FORCEPROP 1 LAST OFFPAGE TRUE
J 0
(-6175 1775);
DISPLAY 0.872340 (-6175 1775);
DISPLAY INVISIBLE (-6175 1775);
FORCEPROP 2 LAST PATH I30
J 0
(-6775 1950);
DISPLAY 1.021277 (-6775 1950);
DISPLAY INVISIBLE (-6775 1950);
FORCEADD OFFPAGE..1
(-6500 1850);
FORCEPROP 2 LAST $XR0 246 
J 0
(-6782 1850);
DISPLAY 0.638298 (-6782 1850);
PAINT MONO (-6782 1850);
FORCEPROP 2 LAST CDS_LIB standard
J 0
(-6500 1850);
DISPLAY INVISIBLE (-6500 1850);
FORCEPROP 1 LAST OFFPAGE TRUE
J 0
(-6175 1725);
DISPLAY 0.872340 (-6175 1725);
DISPLAY INVISIBLE (-6175 1725);
FORCEPROP 1 LAST COMMENT_BODY TRUE
J 0
(-6375 1750);
DISPLAY 0.872340 (-6375 1750);
PAINT GREEN (-6375 1750);
DISPLAY INVISIBLE (-6375 1750);
FORCEPROP 2 LAST PATH I31
J 0
(-6775 1900);
DISPLAY 1.021277 (-6775 1900);
DISPLAY INVISIBLE (-6775 1900);
FORCEADD OFFPAGE..5
(-6500 1950);
FORCEPROP 2 LAST $XR0 250 
J 0
(-6755 1950);
DISPLAY 0.638298 (-6755 1950);
PAINT MONO (-6755 1950);
FORCEPROP 2 LAST CDS_LIB standard
J 0
(-6500 1950);
DISPLAY INVISIBLE (-6500 1950);
FORCEPROP 1 LAST OFFPAGE TRUE
J 0
(-6175 1825);
DISPLAY 0.872340 (-6175 1825);
DISPLAY INVISIBLE (-6175 1825);
FORCEPROP 1 LAST COMMENT_BODY TRUE
J 0
(-6400 1875);
DISPLAY 0.872340 (-6400 1875);
PAINT GREEN (-6400 1875);
DISPLAY INVISIBLE (-6400 1875);
FORCEPROP 2 LAST PATH I32
J 0
(-6750 2000);
DISPLAY 1.021277 (-6750 2000);
DISPLAY INVISIBLE (-6750 2000);
FORCEADD OFFPAGE..1
(-6500 2000);
FORCEPROP 2 LAST $XR0 240 
J 0
(-6782 2000);
DISPLAY 0.638298 (-6782 2000);
PAINT MONO (-6782 2000);
FORCEPROP 2 LAST $XR1 224 
J 0
(-6902 2000);
DISPLAY 0.638298 (-6902 2000);
PAINT MONO (-6902 2000);
FORCEPROP 2 LAST CDS_LIB standard
J 0
(-6500 2000);
DISPLAY INVISIBLE (-6500 2000);
FORCEPROP 1 LAST COMMENT_BODY TRUE
J 0
(-6375 1900);
DISPLAY 0.872340 (-6375 1900);
PAINT GREEN (-6375 1900);
DISPLAY INVISIBLE (-6375 1900);
FORCEPROP 1 LAST OFFPAGE TRUE
J 0
(-6175 1875);
DISPLAY 0.872340 (-6175 1875);
DISPLAY INVISIBLE (-6175 1875);
FORCEPROP 2 LAST PATH I33
J 0
(-6775 2050);
DISPLAY 1.021277 (-6775 2050);
DISPLAY INVISIBLE (-6775 2050);
FORCEADD Q_RES..1
(-5200 1900);
FORCEPROP 1 LAST PART_NUMBER CS00002JB13
J 0
(-5325 1750);
DISPLAY 0.510638 (-5325 1750);
DISPLAY INVISIBLE (-5325 1750);
FORCEPROP 1 LAST MATERIAL CHIP
J 0
(-4900 1900);
DISPLAY 0.404255 (-4900 1900);
FORCEPROP 1 LAST TOLERANCE 5%
J 0
(-4975 1900);
DISPLAY 0.404255 (-4975 1900);
FORCEPROP 1 LAST VALUE 0
J 2
(-5025 1900);
DISPLAY 0.404255 (-5025 1900);
FORCEPROP 1 LAST $LOCATION R2905
J 0
(-5400 1900);
DISPLAY 0.638298 (-5400 1900);
FORCEPROP 1 LASTPIN (-5300 1900) $PN 1
J 0
(-5288 1912);
DISPLAY 0.787234 (-5288 1912);
PAINT MONO (-5288 1912);
FORCEPROP 1 LASTPIN (-5100 1900) $PN 2
J 0
(-5138 1912);
DISPLAY 0.787234 (-5138 1912);
PAINT MONO (-5138 1912);
FORCEPROP 1 LAST WATTAGE 1/16W
J 2
(-5225 1750);
DISPLAY 0.978723 (-5225 1750);
DISPLAY INVISIBLE (-5225 1750);
FORCEPROP 1 LAST PACK_TYPE 0402LF
J 0
(-4950 1900);
DISPLAY 0.638298 (-4950 1900);
DISPLAY INVISIBLE (-4950 1900);
FORCEPROP 2 LAST CDS_LIB pure_quanta
J 0
(-5200 1900);
DISPLAY INVISIBLE (-5200 1900);
FORCEPROP 1 LAST PATH I34
J 0
(-5250 2050);
DISPLAY 0.978723 (-5250 2050);
PAINT WHITE (-5250 2050);
DISPLAY INVISIBLE (-5250 2050);
FORCEPROP 2 LAST CDS_LOCATION R2905
J 0
(-5250 2100);
DISPLAY 1.021277 (-5250 2100);
DISPLAY INVISIBLE (-5250 2100);
FORCEPROP 2 LAST $SEC 1
J 0
(-5250 2100);
DISPLAY 0.680851 (-5250 2100);
PAINT MONO (-5250 2100);
DISPLAY INVISIBLE (-5250 2100);
FORCEPROP 2 LAST CDS_SEC 1
J 0
(-5250 2100);
DISPLAY 1.021277 (-5250 2100);
DISPLAY INVISIBLE (-5250 2100);
FORCEADD Q_RES..1
(-5200 2000);
FORCEPROP 1 LAST PART_NUMBER CS00002JB13
J 0
(-5325 1850);
DISPLAY 0.510638 (-5325 1850);
DISPLAY INVISIBLE (-5325 1850);
FORCEPROP 1 LAST TOLERANCE 5%
J 0
(-4975 2000);
DISPLAY 0.404255 (-4975 2000);
FORCEPROP 1 LAST VALUE 0
J 2
(-5025 2000);
DISPLAY 0.404255 (-5025 2000);
FORCEPROP 1 LAST MATERIAL CHIP
J 0
(-4900 2000);
DISPLAY 0.404255 (-4900 2000);
FORCEPROP 1 LAST $LOCATION R4721
J 0
(-5375 2000);
DISPLAY 0.638298 (-5375 2000);
FORCEPROP 1 LASTPIN (-5300 2000) $PN 1
J 0
(-5288 2012);
DISPLAY 0.787234 (-5288 2012);
PAINT MONO (-5288 2012);
FORCEPROP 1 LASTPIN (-5100 2000) $PN 2
J 0
(-5138 2012);
DISPLAY 0.787234 (-5138 2012);
PAINT MONO (-5138 2012);
FORCEPROP 1 LAST PACK_TYPE 0402LF
J 0
(-4950 2000);
DISPLAY 0.638298 (-4950 2000);
DISPLAY INVISIBLE (-4950 2000);
FORCEPROP 1 LAST WATTAGE 1/16W
J 2
(-5225 1850);
DISPLAY 0.978723 (-5225 1850);
DISPLAY INVISIBLE (-5225 1850);
FORCEPROP 2 LAST CDS_LIB pure_quanta
J 0
(-5200 2000);
DISPLAY INVISIBLE (-5200 2000);
FORCEPROP 1 LAST PATH I35
J 0
(-5250 2150);
DISPLAY 0.978723 (-5250 2150);
PAINT WHITE (-5250 2150);
DISPLAY INVISIBLE (-5250 2150);
FORCEPROP 0 LAST CDS_LOCATION R4721
J 0
(-5375 2050);
DISPLAY 1.021277 (-5375 2050);
DISPLAY INVISIBLE (-5375 2050);
FORCEPROP 0 LAST $SEC 1
J 0
(-5375 2050);
DISPLAY 0.680851 (-5375 2050);
PAINT MONO (-5375 2050);
DISPLAY INVISIBLE (-5375 2050);
FORCEPROP 0 LAST CDS_SEC 1
J 0
(-5375 2050);
DISPLAY 1.021277 (-5375 2050);
DISPLAY INVISIBLE (-5375 2050);
FORCEADD UNIVERSAL_POWER..1
(-2325 1700);
FORCEPROP 3 LASTPIN (-2325 1650) SIG_NAME P12V_PSU\g
J 0
(-2315 1660);
DISPLAY 0.659574 (-2315 1660);
PAINT MONO (-2315 1660);
DISPLAY INVISIBLE (-2315 1660);
FORCEPROP 1 LAST HDL_POWER P12V_PSU
J 1
(-2325 1750);
DISPLAY 0.872340 (-2325 1750);
PAINT GREEN (-2325 1750);
FORCEPROP 2 LAST CDS_LIB logical_power
J 0
(-2325 1700);
DISPLAY INVISIBLE (-2325 1700);
FORCEPROP 1 LAST PATH I36
J 0
(-2275 1725);
DISPLAY 0.872340 (-2275 1725);
PAINT AQUA (-2275 1725);
DISPLAY INVISIBLE (-2275 1725);
FORCEADD Q_RES..1
(-1600 1850);
FORCEPROP 1 LAST PART_NUMBER CS00002JB13
J 0
(-1725 1700);
DISPLAY 0.510638 (-1725 1700);
DISPLAY INVISIBLE (-1725 1700);
FORCEPROP 1 LAST VALUE 0
J 2
(-1425 1850);
DISPLAY 0.404255 (-1425 1850);
FORCEPROP 1 LAST TOLERANCE 5%
J 0
(-1375 1850);
DISPLAY 0.404255 (-1375 1850);
FORCEPROP 1 LAST MATERIAL CHIP
J 0
(-1300 1850);
DISPLAY 0.404255 (-1300 1850);
FORCEPROP 1 LAST $LOCATION R2906
J 0
(-1825 1850);
DISPLAY 0.638298 (-1825 1850);
FORCEPROP 1 LASTPIN (-1700 1850) $PN 1
J 0
(-1688 1862);
DISPLAY 0.787234 (-1688 1862);
PAINT MONO (-1688 1862);
FORCEPROP 1 LASTPIN (-1500 1850) $PN 2
J 0
(-1538 1862);
DISPLAY 0.787234 (-1538 1862);
PAINT MONO (-1538 1862);
FORCEPROP 2 LAST CDS_LIB pure_quanta
J 0
(-1600 1850);
DISPLAY INVISIBLE (-1600 1850);
FORCEPROP 1 LAST WATTAGE 1/16W
J 2
(-1625 1700);
DISPLAY 0.978723 (-1625 1700);
DISPLAY INVISIBLE (-1625 1700);
FORCEPROP 1 LAST PACK_TYPE 0402LF
J 0
(-1350 1850);
DISPLAY 0.638298 (-1350 1850);
DISPLAY INVISIBLE (-1350 1850);
FORCEPROP 1 LAST PATH I37
J 0
(-1650 2000);
DISPLAY 0.978723 (-1650 2000);
PAINT WHITE (-1650 2000);
DISPLAY INVISIBLE (-1650 2000);
FORCEPROP 2 LAST CDS_LOCATION R2906
J 0
(-1650 2050);
DISPLAY 1.021277 (-1650 2050);
DISPLAY INVISIBLE (-1650 2050);
FORCEPROP 2 LAST $SEC 1
J 0
(-1650 2050);
DISPLAY 0.680851 (-1650 2050);
PAINT MONO (-1650 2050);
DISPLAY INVISIBLE (-1650 2050);
FORCEPROP 2 LAST CDS_SEC 1
J 0
(-1650 2050);
DISPLAY 1.021277 (-1650 2050);
DISPLAY INVISIBLE (-1650 2050);
FORCEADD Q_RES..1
(-1600 1900);
FORCEPROP 1 LAST PART_NUMBER CS00002JB13
J 0
(-1725 1750);
DISPLAY 0.510638 (-1725 1750);
DISPLAY INVISIBLE (-1725 1750);
FORCEPROP 1 LAST MATERIAL CHIP
J 0
(-1300 1900);
DISPLAY 0.404255 (-1300 1900);
FORCEPROP 1 LAST TOLERANCE 5%
J 0
(-1375 1900);
DISPLAY 0.404255 (-1375 1900);
FORCEPROP 1 LAST VALUE 0
J 2
(-1425 1900);
DISPLAY 0.404255 (-1425 1900);
FORCEPROP 1 LAST $LOCATION R2803
J 0
(-1825 1900);
DISPLAY 0.638298 (-1825 1900);
FORCEPROP 1 LASTPIN (-1700 1900) $PN 1
J 0
(-1688 1912);
DISPLAY 0.787234 (-1688 1912);
FORCEPROP 1 LASTPIN (-1500 1900) $PN 2
J 0
(-1538 1912);
DISPLAY 0.787234 (-1538 1912);
FORCEPROP 1 LAST PACK_TYPE 0402LF
J 0
(-1350 1900);
DISPLAY 0.638298 (-1350 1900);
DISPLAY INVISIBLE (-1350 1900);
FORCEPROP 1 LAST WATTAGE 1/16W
J 2
(-1625 1750);
DISPLAY 0.978723 (-1625 1750);
DISPLAY INVISIBLE (-1625 1750);
FORCEPROP 2 LAST CDS_LIB pure_quanta
J 0
(-1600 1900);
PAINT MONO (-1600 1900);
DISPLAY INVISIBLE (-1600 1900);
FORCEPROP 1 LAST PATH I38
J 0
(-1650 2050);
DISPLAY 0.978723 (-1650 2050);
PAINT WHITE (-1650 2050);
DISPLAY INVISIBLE (-1650 2050);
FORCEPROP 1 LAST $LOCATION R2803
J 0
(-1650 2100);
DISPLAY 1.021277 (-1650 2100);
DISPLAY INVISIBLE (-1650 2100);
FORCEPROP 2 LAST CDS_LOCATION R2803
J 0
(-1650 2100);
DISPLAY 1.021277 (-1650 2100);
DISPLAY INVISIBLE (-1650 2100);
FORCEPROP 2 LAST $SEC 1
J 0
(-1650 2100);
DISPLAY 0.680851 (-1650 2100);
PAINT MONO (-1650 2100);
DISPLAY INVISIBLE (-1650 2100);
FORCEPROP 2 LAST CDS_SEC 1
J 0
(-1650 2100);
DISPLAY 1.021277 (-1650 2100);
DISPLAY INVISIBLE (-1650 2100);
FORCEADD Q_RES..1
(-1600 1950);
FORCEPROP 1 LAST PART_NUMBER CS00002JB13
J 0
(-1725 1800);
DISPLAY 0.510638 (-1725 1800);
DISPLAY INVISIBLE (-1725 1800);
FORCEPROP 1 LAST MATERIAL CHIP
J 0
(-1300 1950);
DISPLAY 0.404255 (-1300 1950);
FORCEPROP 1 LAST VALUE 0
J 2
(-1425 1950);
DISPLAY 0.404255 (-1425 1950);
FORCEPROP 1 LAST TOLERANCE 5%
J 0
(-1375 1950);
DISPLAY 0.404255 (-1375 1950);
FORCEPROP 1 LAST $LOCATION R2802
J 0
(-1825 1950);
DISPLAY 0.638298 (-1825 1950);
FORCEPROP 1 LASTPIN (-1700 1950) $PN 1
J 0
(-1688 1962);
DISPLAY 0.787234 (-1688 1962);
FORCEPROP 1 LASTPIN (-1500 1950) $PN 2
J 0
(-1538 1962);
DISPLAY 0.787234 (-1538 1962);
FORCEPROP 1 LAST WATTAGE 1/16W
J 2
(-1625 1800);
DISPLAY 0.978723 (-1625 1800);
DISPLAY INVISIBLE (-1625 1800);
FORCEPROP 1 LAST PACK_TYPE 0402LF
J 0
(-1350 1950);
DISPLAY 0.638298 (-1350 1950);
DISPLAY INVISIBLE (-1350 1950);
FORCEPROP 2 LAST CDS_LIB pure_quanta
J 0
(-1600 1950);
PAINT MONO (-1600 1950);
DISPLAY INVISIBLE (-1600 1950);
FORCEPROP 1 LAST PATH I39
J 0
(-1650 2100);
DISPLAY 0.978723 (-1650 2100);
PAINT WHITE (-1650 2100);
DISPLAY INVISIBLE (-1650 2100);
FORCEPROP 1 LAST $LOCATION R2802
J 0
(-1650 2150);
DISPLAY 1.021277 (-1650 2150);
DISPLAY INVISIBLE (-1650 2150);
FORCEPROP 2 LAST CDS_LOCATION R2802
J 0
(-1650 2150);
DISPLAY 1.021277 (-1650 2150);
DISPLAY INVISIBLE (-1650 2150);
FORCEPROP 2 LAST $SEC 1
J 0
(-1650 2150);
DISPLAY 0.680851 (-1650 2150);
PAINT MONO (-1650 2150);
DISPLAY INVISIBLE (-1650 2150);
FORCEPROP 2 LAST CDS_SEC 1
J 0
(-1650 2150);
DISPLAY 1.021277 (-1650 2150);
DISPLAY INVISIBLE (-1650 2150);
FORCEADD Q_RES..2
(-5800 -1700);
FORCEPROP 1 LAST PART_NUMBER CS24702JB10
J 0
(-5760 -1825);
DISPLAY 0.638298 (-5760 -1825);
DISPLAY INVISIBLE (-5760 -1825);
FORCEPROP 1 LAST VALUE 4.7K
J 0
(-5755 -1625);
DISPLAY 0.638298 (-5755 -1625);
FORCEPROP 1 LAST TOLERANCE 5%
J 0
(-5755 -1675);
DISPLAY 0.638298 (-5755 -1675);
FORCEPROP 1 LAST MATERIAL EMPTY
J 0
(-5760 -1775);
DISPLAY 0.638298 (-5760 -1775);
FORCEPROP 1 LAST WATTAGE 1/16W
J 0
(-5760 -1725);
DISPLAY 0.638298 (-5760 -1725);
FORCEPROP 1 LAST PACK_TYPE 0402LF
J 0
(-5760 -1875);
DISPLAY 0.638298 (-5760 -1875);
FORCEPROP 1 LAST $LOCATION R2950
J 0
(-5755 -1575);
DISPLAY 0.978723 (-5755 -1575);
FORCEPROP 1 LASTPIN (-5800 -1600) $PN 1
J 0
(-5795 -1638);
DISPLAY 0.787234 (-5795 -1638);
PAINT MONO (-5795 -1638);
FORCEPROP 1 LASTPIN (-5800 -1800) $PN 2
J 0
(-5795 -1790);
DISPLAY 0.787234 (-5795 -1790);
PAINT MONO (-5795 -1790);
FORCEPROP 2 LAST CDS_LIB pure_quanta
J 0
(-5800 -1700);
DISPLAY INVISIBLE (-5800 -1700);
FORCEPROP 1 LAST PATH I4
J 0
(-5750 -1525);
DISPLAY 0.978723 (-5750 -1525);
PAINT WHITE (-5750 -1525);
DISPLAY INVISIBLE (-5750 -1525);
FORCEPROP 0 LAST CDS_LOCATION R2950
J 0
(-5750 -1525);
DISPLAY 1.021277 (-5750 -1525);
DISPLAY INVISIBLE (-5750 -1525);
FORCEPROP 0 LAST $SEC 1
J 0
(-5750 -1525);
DISPLAY 0.680851 (-5750 -1525);
PAINT MONO (-5750 -1525);
DISPLAY INVISIBLE (-5750 -1525);
FORCEPROP 0 LAST CDS_SEC 1
J 0
(-5750 -1525);
DISPLAY 1.021277 (-5750 -1525);
DISPLAY INVISIBLE (-5750 -1525);
FORCEADD OFFPAGE..5
(-500 1325);
FORCEPROP 2 LAST $XR0 245 
J 0
(-755 1325);
DISPLAY 0.638298 (-755 1325);
PAINT MONO (-755 1325);
FORCEPROP 2 LAST CDS_LIB standard
J 2
(-500 1325);
DISPLAY INVISIBLE (-500 1325);
FORCEPROP 1 LAST COMMENT_BODY TRUE
J 0
(-400 1250);
DISPLAY 0.872340 (-400 1250);
PAINT GREEN (-400 1250);
DISPLAY INVISIBLE (-400 1250);
FORCEPROP 1 LAST OFFPAGE TRUE
J 0
(-175 1200);
DISPLAY 0.872340 (-175 1200);
DISPLAY INVISIBLE (-175 1200);
FORCEPROP 2 LAST PATH I40
J 0
(-750 1375);
DISPLAY 1.021277 (-750 1375);
DISPLAY INVISIBLE (-750 1375);
FORCEADD Q_RES..2
(-1175 2350);
FORCEPROP 1 LAST PART_NUMBER CS24702JB10
J 0
(-1135 2175);
DISPLAY 0.638298 (-1135 2175);
DISPLAY INVISIBLE (-1135 2175);
FORCEPROP 1 LAST PACK_TYPE 0402LF
J 0
(-1135 2225);
DISPLAY 0.638298 (-1135 2225);
FORCEPROP 1 LAST VALUE 4.7K
J 0
(-1130 2425);
DISPLAY 0.638298 (-1130 2425);
FORCEPROP 1 LAST TOLERANCE 5%
J 0
(-1130 2375);
DISPLAY 0.638298 (-1130 2375);
FORCEPROP 1 LAST MATERIAL CHIP
J 0
(-1135 2275);
DISPLAY 0.638298 (-1135 2275);
FORCEPROP 1 LAST WATTAGE 1/16W
J 0
(-1135 2325);
DISPLAY 0.638298 (-1135 2325);
FORCEPROP 1 LAST $LOCATION R4701
J 0
(-1130 2475);
DISPLAY 0.978723 (-1130 2475);
FORCEPROP 1 LASTPIN (-1175 2450) $PN 1
J 0
(-1170 2412);
DISPLAY 0.787234 (-1170 2412);
PAINT MONO (-1170 2412);
FORCEPROP 1 LASTPIN (-1175 2250) $PN 2
J 0
(-1170 2260);
DISPLAY 0.787234 (-1170 2260);
PAINT MONO (-1170 2260);
FORCEPROP 2 LAST CDS_LIB pure_quanta
J 0
(-1175 2350);
DISPLAY INVISIBLE (-1175 2350);
FORCEPROP 1 LAST PATH I41
J 0
(-1125 2525);
DISPLAY 0.978723 (-1125 2525);
PAINT WHITE (-1125 2525);
DISPLAY INVISIBLE (-1125 2525);
FORCEPROP 0 LAST CDS_LOCATION R4701
J 0
(-1125 2525);
DISPLAY 1.021277 (-1125 2525);
DISPLAY INVISIBLE (-1125 2525);
FORCEPROP 0 LAST $SEC 1
J 0
(-1125 2525);
DISPLAY 0.680851 (-1125 2525);
PAINT MONO (-1125 2525);
DISPLAY INVISIBLE (-1125 2525);
FORCEPROP 0 LAST CDS_SEC 1
J 0
(-1125 2525);
DISPLAY 1.021277 (-1125 2525);
DISPLAY INVISIBLE (-1125 2525);
FORCEADD UNIVERSAL_POWER..1
(-1175 2650);
FORCEPROP 3 LASTPIN (-1175 2600) SIG_NAME P3V3_AUX\g
J 0
(-1165 2610);
DISPLAY 0.659574 (-1165 2610);
PAINT MONO (-1165 2610);
DISPLAY INVISIBLE (-1165 2610);
FORCEPROP 1 LAST HDL_POWER P3V3_AUX
J 1
(-1175 2700);
DISPLAY 0.872340 (-1175 2700);
PAINT GREEN (-1175 2700);
FORCEPROP 2 LAST CDS_LIB logical_power
J 0
(-1175 2650);
DISPLAY INVISIBLE (-1175 2650);
FORCEPROP 1 LAST PATH I42
J 0
(-1125 2675);
DISPLAY 0.872340 (-1125 2675);
PAINT AQUA (-1125 2675);
DISPLAY INVISIBLE (-1125 2675);
FORCEADD OFFPAGE..5
R 2
(-325 1950);
FORCEPROP 2 LAST $XR0 246 
J 0
(-136 1950);
DISPLAY 0.638298 (-136 1950);
PAINT MONO (-136 1950);
FORCEPROP 2 LAST CDS_LIB standard
J 0
(-325 1950);
DISPLAY INVISIBLE (-325 1950);
FORCEPROP 1 LAST OFFPAGE TRUE
J 2
(-650 1825);
DISPLAY 0.872340 (-650 1825);
DISPLAY INVISIBLE (-650 1825);
FORCEPROP 1 LAST COMMENT_BODY TRUE
J 2
(-425 1875);
DISPLAY 0.872340 (-425 1875);
PAINT GREEN (-425 1875);
DISPLAY INVISIBLE (-425 1875);
FORCEPROP 2 LAST PATH I43
J 0
(-125 2000);
DISPLAY 1.021277 (-125 2000);
DISPLAY INVISIBLE (-125 2000);
FORCEADD OFFPAGE..5
R 2
(-325 1800);
FORCEPROP 2 LAST $XR0 245 
J 0
(-136 1800);
DISPLAY 0.638298 (-136 1800);
PAINT MONO (-136 1800);
FORCEPROP 2 LAST $XR1 301 
J 0
(-16 1800);
DISPLAY 0.638298 (-16 1800);
PAINT MONO (-16 1800);
FORCEPROP 1 LAST COMMENT_BODY TRUE
J 2
(-425 1725);
DISPLAY 0.872340 (-425 1725);
PAINT GREEN (-425 1725);
DISPLAY INVISIBLE (-425 1725);
FORCEPROP 1 LAST OFFPAGE TRUE
J 2
(-650 1675);
DISPLAY 0.872340 (-650 1675);
DISPLAY INVISIBLE (-650 1675);
FORCEPROP 2 LAST CDS_LIB standard
J 2
(-325 1800);
DISPLAY INVISIBLE (-325 1800);
FORCEPROP 2 LAST PATH I44
J 0
(0 1850);
DISPLAY 1.021277 (0 1850);
DISPLAY INVISIBLE (0 1850);
FORCEADD OFFPAGE..4
(-325 1850);
FORCEPROP 2 LAST $XR0 246 
J 0
(-139 1850);
DISPLAY 0.638298 (-139 1850);
PAINT MONO (-139 1850);
FORCEPROP 1 LAST OFFPAGE TRUE
J 0
(0 1725);
DISPLAY 0.872340 (0 1725);
PAINT GREEN (0 1725);
DISPLAY INVISIBLE (0 1725);
FORCEPROP 1 LAST COMMENT_BODY TRUE
J 0
(-350 1750);
DISPLAY 0.872340 (-350 1750);
PAINT PEACH (-350 1750);
DISPLAY INVISIBLE (-350 1750);
FORCEPROP 2 LAST CDS_LIB standard
J 0
(-325 1850);
DISPLAY INVISIBLE (-325 1850);
FORCEPROP 2 LAST PATH I45
J 0
(-125 1900);
DISPLAY 1.021277 (-125 1900);
DISPLAY INVISIBLE (-125 1900);
FORCEADD OFFPAGE..4
(-325 1900);
FORCEPROP 2 LAST $XR0 213 
J 0
(-139 1900);
DISPLAY 0.638298 (-139 1900);
PAINT MONO (-139 1900);
FORCEPROP 1 LAST OFFPAGE TRUE
J 0
(0 1775);
DISPLAY 0.872340 (0 1775);
PAINT GREEN (0 1775);
DISPLAY INVISIBLE (0 1775);
FORCEPROP 1 LAST COMMENT_BODY TRUE
J 0
(-350 1800);
DISPLAY 0.872340 (-350 1800);
PAINT PEACH (-350 1800);
DISPLAY INVISIBLE (-350 1800);
FORCEPROP 2 LAST CDS_LIB standard
J 0
(-325 1900);
DISPLAY INVISIBLE (-325 1900);
FORCEPROP 2 LAST PATH I46
J 0
(-125 1950);
DISPLAY 1.021277 (-125 1950);
DISPLAY INVISIBLE (-125 1950);
FORCEADD OFFPAGE..3
(-350 2000);
FORCEPROP 2 LAST $XR0 245 
J 0
(-136 2000);
DISPLAY 0.638298 (-136 2000);
PAINT MONO (-136 2000);
FORCEPROP 2 LAST CDS_LIB standard
J 0
(-350 2000);
DISPLAY INVISIBLE (-350 2000);
FORCEPROP 1 LAST COMMENT_BODY TRUE
J 0
(-400 1900);
DISPLAY 0.872340 (-400 1900);
PAINT GREEN (-400 1900);
DISPLAY INVISIBLE (-400 1900);
FORCEPROP 1 LAST OFFPAGE TRUE
J 0
(-25 1875);
DISPLAY 0.872340 (-25 1875);
PAINT GREEN (-25 1875);
DISPLAY INVISIBLE (-25 1875);
FORCEPROP 2 LAST PATH I47
J 0
(-125 2050);
DISPLAY 1.021277 (-125 2050);
DISPLAY INVISIBLE (-125 2050);
FORCEADD OFFPAGE..4
(-350 2050);
FORCEPROP 2 LAST $XR0 245 
J 0
(-164 2050);
DISPLAY 0.638298 (-164 2050);
PAINT MONO (-164 2050);
FORCEPROP 2 LAST CDS_LIB standard
J 0
(-350 2050);
DISPLAY INVISIBLE (-350 2050);
FORCEPROP 1 LAST OFFPAGE TRUE
J 0
(-25 1925);
DISPLAY 0.872340 (-25 1925);
PAINT GREEN (-25 1925);
DISPLAY INVISIBLE (-25 1925);
FORCEPROP 1 LAST COMMENT_BODY TRUE
J 0
(-375 1950);
DISPLAY 0.872340 (-375 1950);
PAINT PEACH (-375 1950);
DISPLAY INVISIBLE (-375 1950);
FORCEPROP 2 LAST PATH I48
J 0
(-150 2100);
DISPLAY 1.021277 (-150 2100);
DISPLAY INVISIBLE (-150 2100);
FORCEADD OFFPAGE..3
(1025 -2225);
FORCEPROP 2 LAST $XR0 245 
J 0
(1239 -2225);
DISPLAY 0.638298 (1239 -2225);
PAINT MONO (1239 -2225);
FORCEPROP 1 LAST OFFPAGE TRUE
J 0
(1350 -2350);
DISPLAY 0.872340 (1350 -2350);
PAINT GREEN (1350 -2350);
DISPLAY INVISIBLE (1350 -2350);
FORCEPROP 1 LAST COMMENT_BODY TRUE
J 0
(975 -2325);
DISPLAY 0.872340 (975 -2325);
PAINT GREEN (975 -2325);
DISPLAY INVISIBLE (975 -2325);
FORCEPROP 2 LAST CDS_LIB standard
J 0
(1025 -2225);
DISPLAY INVISIBLE (1025 -2225);
FORCEPROP 2 LAST PATH I49
J 0
(1250 -2175);
DISPLAY 1.021277 (1250 -2175);
DISPLAY INVISIBLE (1250 -2175);
FORCEADD UNIVERSAL_POWER..1
(-5800 -1425);
FORCEPROP 3 LASTPIN (-5800 -1475) SIG_NAME P3V3_AUX\g
J 0
(-5790 -1465);
DISPLAY 0.659574 (-5790 -1465);
PAINT MONO (-5790 -1465);
DISPLAY INVISIBLE (-5790 -1465);
FORCEPROP 1 LAST HDL_POWER P3V3_AUX
J 1
(-5800 -1375);
DISPLAY 0.872340 (-5800 -1375);
PAINT GREEN (-5800 -1375);
FORCEPROP 2 LAST CDS_LIB logical_power
J 0
(-5800 -1425);
DISPLAY INVISIBLE (-5800 -1425);
FORCEPROP 1 LAST PATH I5
J 0
(-5750 -1400);
DISPLAY 0.872340 (-5750 -1400);
PAINT AQUA (-5750 -1400);
DISPLAY INVISIBLE (-5750 -1400);
FORCEADD OFFPAGE..4
(1025 -2125);
FORCEPROP 2 LAST $XR0 245 
J 0
(1211 -2125);
DISPLAY 0.638298 (1211 -2125);
PAINT MONO (1211 -2125);
FORCEPROP 1 LAST COMMENT_BODY TRUE
J 0
(1000 -2225);
DISPLAY 0.872340 (1000 -2225);
PAINT PEACH (1000 -2225);
DISPLAY INVISIBLE (1000 -2225);
FORCEPROP 1 LAST OFFPAGE TRUE
J 0
(1350 -2250);
DISPLAY 0.872340 (1350 -2250);
PAINT GREEN (1350 -2250);
DISPLAY INVISIBLE (1350 -2250);
FORCEPROP 2 LAST CDS_LIB standard
J 0
(1025 -2125);
DISPLAY INVISIBLE (1025 -2125);
FORCEPROP 2 LAST PATH I50
J 0
(1225 -2075);
DISPLAY 1.021277 (1225 -2075);
DISPLAY INVISIBLE (1225 -2075);
FORCEADD Q_CAP..2
(750 550);
FORCEPROP 1 LAST PART_NUMBER CH4104K1B00
J 1
(750 600);
DISPLAY 0.978723 (750 600);
DISPLAY INVISIBLE (750 600);
FORCEPROP 1 LAST VALUE 0.1UF
J 2
(750 450);
DISPLAY 0.638298 (750 450);
FORCEPROP 1 LAST MATERIAL EMPTY
J 0
(775 450);
DISPLAY 0.638298 (775 450);
PAINT RED (775 450);
FORCEPROP 1 LAST $LOCATION C2371
J 1
(600 550);
DISPLAY 0.787234 (600 550);
FORCEPROP 1 LASTPIN (650 550) $PN 1
J 0
(640 565);
DISPLAY 0.787234 (640 565);
PAINT MONO (640 565);
FORCEPROP 1 LASTPIN (850 550) $PN 2
J 0
(835 565);
DISPLAY 0.787234 (835 565);
PAINT MONO (835 565);
FORCEPROP 2 LAST CDS_LIB pure_quanta
J 0
(750 550);
DISPLAY INVISIBLE (750 550);
FORCEPROP 1 LAST PACK_TYPE 0402
J 1
(750 350);
DISPLAY 0.978723 (750 350);
DISPLAY INVISIBLE (750 350);
FORCEPROP 1 LAST TOLERANCE 10%
J 2
(750 400);
DISPLAY 0.978723 (750 400);
DISPLAY INVISIBLE (750 400);
FORCEPROP 1 LAST VOLTAGE 25V
J 0
(750 450);
DISPLAY 0.978723 (750 450);
DISPLAY INVISIBLE (750 450);
FORCEPROP 1 LAST PATH I51
J 0
(750 750);
DISPLAY 0.978723 (750 750);
PAINT WHITE (750 750);
DISPLAY INVISIBLE (750 750);
FORCEPROP 0 LAST CDS_LOCATION C2371
J 0
(600 600);
DISPLAY 1.021277 (600 600);
DISPLAY INVISIBLE (600 600);
FORCEPROP 0 LAST $SEC 1
J 0
(600 600);
DISPLAY 0.680851 (600 600);
PAINT MONO (600 600);
DISPLAY INVISIBLE (600 600);
FORCEPROP 0 LAST CDS_SEC 1
J 0
(600 600);
DISPLAY 1.021277 (600 600);
DISPLAY INVISIBLE (600 600);
FORCEADD Q_CAP..2
(750 725);
FORCEPROP 1 LAST PART_NUMBER CH4104K1B00
J 1
(750 775);
DISPLAY 0.978723 (750 775);
DISPLAY INVISIBLE (750 775);
FORCEPROP 1 LAST VALUE 0.1UF
J 2
(750 625);
DISPLAY 0.638298 (750 625);
FORCEPROP 1 LAST MATERIAL EMPTY
J 0
(775 625);
DISPLAY 0.638298 (775 625);
PAINT RED (775 625);
FORCEPROP 1 LAST $LOCATION C2297
J 1
(600 725);
DISPLAY 0.638298 (600 725);
FORCEPROP 1 LASTPIN (650 725) $PN 1
J 0
(640 740);
DISPLAY 0.787234 (640 740);
PAINT MONO (640 740);
FORCEPROP 1 LASTPIN (850 725) $PN 2
J 0
(835 740);
DISPLAY 0.787234 (835 740);
PAINT MONO (835 740);
FORCEPROP 1 LAST VOLTAGE 25V
J 0
(750 625);
DISPLAY 0.978723 (750 625);
DISPLAY INVISIBLE (750 625);
FORCEPROP 1 LAST TOLERANCE 10%
J 2
(750 575);
DISPLAY 0.978723 (750 575);
DISPLAY INVISIBLE (750 575);
FORCEPROP 1 LAST PACK_TYPE 0402
J 1
(750 525);
DISPLAY 0.978723 (750 525);
DISPLAY INVISIBLE (750 525);
FORCEPROP 2 LAST CDS_LIB pure_quanta
J 0
(750 725);
DISPLAY INVISIBLE (750 725);
FORCEPROP 1 LAST PATH I52
J 0
(750 925);
DISPLAY 0.978723 (750 925);
PAINT WHITE (750 925);
DISPLAY INVISIBLE (750 925);
FORCEPROP 0 LAST CDS_LOCATION C2297
J 0
(600 775);
DISPLAY 1.021277 (600 775);
DISPLAY INVISIBLE (600 775);
FORCEPROP 0 LAST $SEC 1
J 0
(600 775);
DISPLAY 0.680851 (600 775);
PAINT MONO (600 775);
DISPLAY INVISIBLE (600 775);
FORCEPROP 0 LAST CDS_SEC 1
J 0
(600 775);
DISPLAY 1.021277 (600 775);
DISPLAY INVISIBLE (600 775);
FORCEADD Q_CAP..2
(750 875);
FORCEPROP 1 LAST PART_NUMBER CH4104K1B00
J 1
(750 925);
DISPLAY 0.978723 (750 925);
DISPLAY INVISIBLE (750 925);
FORCEPROP 1 LAST VALUE 0.1UF
J 2
(750 775);
DISPLAY 0.638298 (750 775);
FORCEPROP 1 LAST MATERIAL EMPTY
J 0
(775 775);
DISPLAY 0.638298 (775 775);
PAINT RED (775 775);
FORCEPROP 1 LAST $LOCATION C2296
J 1
(600 875);
DISPLAY 0.638298 (600 875);
FORCEPROP 1 LASTPIN (650 875) $PN 1
J 0
(640 890);
DISPLAY 0.787234 (640 890);
PAINT MONO (640 890);
FORCEPROP 1 LASTPIN (850 875) $PN 2
J 0
(835 890);
DISPLAY 0.787234 (835 890);
PAINT MONO (835 890);
FORCEPROP 1 LAST VOLTAGE 25V
J 0
(750 775);
DISPLAY 0.978723 (750 775);
DISPLAY INVISIBLE (750 775);
FORCEPROP 1 LAST TOLERANCE 10%
J 2
(750 725);
DISPLAY 0.978723 (750 725);
DISPLAY INVISIBLE (750 725);
FORCEPROP 1 LAST PACK_TYPE 0402
J 1
(750 675);
DISPLAY 0.978723 (750 675);
DISPLAY INVISIBLE (750 675);
FORCEPROP 2 LAST CDS_LIB pure_quanta
J 0
(750 875);
DISPLAY INVISIBLE (750 875);
FORCEPROP 1 LAST PATH I53
J 0
(750 1075);
DISPLAY 0.978723 (750 1075);
PAINT WHITE (750 1075);
DISPLAY INVISIBLE (750 1075);
FORCEPROP 0 LAST CDS_LOCATION C2296
J 0
(600 925);
DISPLAY 1.021277 (600 925);
DISPLAY INVISIBLE (600 925);
FORCEPROP 0 LAST $SEC 1
J 0
(600 925);
DISPLAY 0.680851 (600 925);
PAINT MONO (600 925);
DISPLAY INVISIBLE (600 925);
FORCEPROP 0 LAST CDS_SEC 1
J 0
(600 925);
DISPLAY 1.021277 (600 925);
DISPLAY INVISIBLE (600 925);
FORCEADD Q_CAP..2
(750 1025);
FORCEPROP 1 LAST PART_NUMBER CH4104K1B00
J 1
(750 1075);
DISPLAY 0.978723 (750 1075);
DISPLAY INVISIBLE (750 1075);
FORCEPROP 1 LAST VALUE 0.1UF
J 2
(750 925);
DISPLAY 0.638298 (750 925);
FORCEPROP 1 LAST MATERIAL EMPTY
J 0
(775 925);
DISPLAY 0.638298 (775 925);
PAINT RED (775 925);
FORCEPROP 1 LAST $LOCATION C2295
J 1
(600 1025);
DISPLAY 0.638298 (600 1025);
FORCEPROP 1 LASTPIN (650 1025) $PN 1
J 0
(640 1040);
DISPLAY 0.787234 (640 1040);
PAINT MONO (640 1040);
FORCEPROP 1 LASTPIN (850 1025) $PN 2
J 0
(835 1040);
DISPLAY 0.787234 (835 1040);
PAINT MONO (835 1040);
FORCEPROP 1 LAST VOLTAGE 25V
J 0
(750 925);
DISPLAY 0.978723 (750 925);
DISPLAY INVISIBLE (750 925);
FORCEPROP 1 LAST TOLERANCE 10%
J 2
(750 875);
DISPLAY 0.978723 (750 875);
DISPLAY INVISIBLE (750 875);
FORCEPROP 1 LAST PACK_TYPE 0402
J 1
(750 825);
DISPLAY 0.978723 (750 825);
DISPLAY INVISIBLE (750 825);
FORCEPROP 2 LAST CDS_LIB pure_quanta
J 0
(750 1025);
DISPLAY INVISIBLE (750 1025);
FORCEPROP 1 LAST PATH I54
J 0
(750 1225);
DISPLAY 0.978723 (750 1225);
PAINT WHITE (750 1225);
DISPLAY INVISIBLE (750 1225);
FORCEPROP 0 LAST CDS_LOCATION C2295
J 0
(600 1075);
DISPLAY 1.021277 (600 1075);
DISPLAY INVISIBLE (600 1075);
FORCEPROP 0 LAST $SEC 1
J 0
(600 1075);
DISPLAY 0.680851 (600 1075);
PAINT MONO (600 1075);
DISPLAY INVISIBLE (600 1075);
FORCEPROP 0 LAST CDS_SEC 1
J 0
(600 1075);
DISPLAY 1.021277 (600 1075);
DISPLAY INVISIBLE (600 1075);
FORCEADD Q_CAP..2
(750 1175);
FORCEPROP 1 LAST PART_NUMBER CH4104K1B00
J 1
(750 1225);
DISPLAY 0.978723 (750 1225);
DISPLAY INVISIBLE (750 1225);
FORCEPROP 1 LAST MATERIAL EMPTY
J 0
(775 1075);
DISPLAY 0.638298 (775 1075);
PAINT RED (775 1075);
FORCEPROP 1 LAST VALUE 0.1UF
J 2
(750 1075);
DISPLAY 0.638298 (750 1075);
FORCEPROP 1 LAST $LOCATION C2294
J 1
(600 1175);
DISPLAY 0.638298 (600 1175);
FORCEPROP 1 LASTPIN (650 1175) $PN 1
J 0
(640 1190);
DISPLAY 0.787234 (640 1190);
PAINT MONO (640 1190);
FORCEPROP 1 LASTPIN (850 1175) $PN 2
J 0
(835 1190);
DISPLAY 0.787234 (835 1190);
PAINT MONO (835 1190);
FORCEPROP 1 LAST VOLTAGE 25V
J 0
(750 1075);
DISPLAY 0.978723 (750 1075);
DISPLAY INVISIBLE (750 1075);
FORCEPROP 1 LAST TOLERANCE 10%
J 2
(750 1025);
DISPLAY 0.978723 (750 1025);
DISPLAY INVISIBLE (750 1025);
FORCEPROP 1 LAST PACK_TYPE 0402
J 1
(750 975);
DISPLAY 0.978723 (750 975);
DISPLAY INVISIBLE (750 975);
FORCEPROP 2 LAST CDS_LIB pure_quanta
J 0
(750 1175);
DISPLAY INVISIBLE (750 1175);
FORCEPROP 1 LAST PATH I55
J 0
(750 1375);
DISPLAY 0.978723 (750 1375);
PAINT WHITE (750 1375);
DISPLAY INVISIBLE (750 1375);
FORCEPROP 0 LAST CDS_LOCATION C2294
J 0
(600 1225);
DISPLAY 1.021277 (600 1225);
DISPLAY INVISIBLE (600 1225);
FORCEPROP 0 LAST $SEC 1
J 0
(600 1225);
DISPLAY 0.680851 (600 1225);
PAINT MONO (600 1225);
DISPLAY INVISIBLE (600 1225);
FORCEPROP 0 LAST CDS_SEC 1
J 0
(600 1225);
DISPLAY 1.021277 (600 1225);
DISPLAY INVISIBLE (600 1225);
FORCEADD UNIVERSAL_GND..1
(1200 350);
FORCEPROP 3 LASTPIN (1200 400) SIG_NAME GND\g
J 0
(1210 410);
DISPLAY 0.659574 (1210 410);
PAINT MONO (1210 410);
DISPLAY INVISIBLE (1210 410);
FORCEPROP 2 LAST CDS_LIB logical_power
J 0
(1200 350);
DISPLAY INVISIBLE (1200 350);
FORCEPROP 1 LAST HDL_POWER GND
J 1
(1225 275);
DISPLAY 0.872340 (1225 275);
PAINT GREEN (1225 275);
DISPLAY INVISIBLE (1225 275);
FORCEPROP 1 LAST PATH I56
J 0
(1275 350);
DISPLAY 0.872340 (1275 350);
PAINT AQUA (1275 350);
DISPLAY INVISIBLE (1275 350);
FORCEADD Q_CAP..2
(750 1325);
FORCEPROP 1 LAST PART_NUMBER CH4104K1B00
J 1
(750 1375);
DISPLAY 0.978723 (750 1375);
DISPLAY INVISIBLE (750 1375);
FORCEPROP 1 LAST VALUE 0.1UF
J 2
(750 1225);
DISPLAY 0.638298 (750 1225);
FORCEPROP 1 LAST MATERIAL EMPTY
J 0
(775 1225);
DISPLAY 0.638298 (775 1225);
PAINT RED (775 1225);
FORCEPROP 1 LAST $LOCATION C2293
J 1
(600 1325);
DISPLAY 0.638298 (600 1325);
FORCEPROP 1 LASTPIN (650 1325) $PN 1
J 0
(640 1340);
DISPLAY 0.787234 (640 1340);
PAINT MONO (640 1340);
FORCEPROP 1 LASTPIN (850 1325) $PN 2
J 0
(835 1340);
DISPLAY 0.787234 (835 1340);
PAINT MONO (835 1340);
FORCEPROP 1 LAST VOLTAGE 25V
J 0
(750 1225);
DISPLAY 0.978723 (750 1225);
DISPLAY INVISIBLE (750 1225);
FORCEPROP 1 LAST TOLERANCE 10%
J 2
(750 1175);
DISPLAY 0.978723 (750 1175);
DISPLAY INVISIBLE (750 1175);
FORCEPROP 1 LAST PACK_TYPE 0402
J 1
(750 1125);
DISPLAY 0.978723 (750 1125);
DISPLAY INVISIBLE (750 1125);
FORCEPROP 2 LAST CDS_LIB pure_quanta
J 0
(750 1325);
DISPLAY INVISIBLE (750 1325);
FORCEPROP 1 LAST PATH I57
J 0
(750 1525);
DISPLAY 0.978723 (750 1525);
PAINT WHITE (750 1525);
DISPLAY INVISIBLE (750 1525);
FORCEPROP 0 LAST CDS_LOCATION C2293
J 0
(600 1400);
DISPLAY 1.021277 (600 1400);
DISPLAY INVISIBLE (600 1400);
FORCEPROP 0 LAST $SEC 1
J 0
(600 1400);
DISPLAY 0.680851 (600 1400);
PAINT MONO (600 1400);
DISPLAY INVISIBLE (600 1400);
FORCEPROP 0 LAST CDS_SEC 1
J 0
(600 1400);
DISPLAY 1.021277 (600 1400);
DISPLAY INVISIBLE (600 1400);
FORCEADD OFFPAGE..3
R 2
(-4950 -2225);
FORCEPROP 2 LAST $XR0 240 
J 0
(-5260 -2225);
DISPLAY 0.638298 (-5260 -2225);
PAINT MONO (-5260 -2225);
FORCEPROP 2 LAST $XR1 241 
J 0
(-5260 -2261);
DISPLAY 0.638298 (-5260 -2261);
PAINT MONO (-5260 -2261);
FORCEPROP 1 LAST OFFPAGE TRUE
J 2
(-5275 -2350);
DISPLAY 0.872340 (-5275 -2350);
PAINT GREEN (-5275 -2350);
DISPLAY INVISIBLE (-5275 -2350);
FORCEPROP 1 LAST COMMENT_BODY TRUE
J 2
(-4900 -2325);
DISPLAY 0.872340 (-4900 -2325);
PAINT GREEN (-4900 -2325);
DISPLAY INVISIBLE (-4900 -2325);
FORCEPROP 2 LAST CDS_LIB standard
J 2
(-4950 -2225);
DISPLAY INVISIBLE (-4950 -2225);
FORCEPROP 2 LAST PATH I6
J 0
(-5250 -2175);
DISPLAY 1.021277 (-5250 -2175);
DISPLAY INVISIBLE (-5250 -2175);
FORCEADD OFFPAGE..4
R 2
(-4950 -2125);
FORCEPROP 2 LAST $XR0 240 
J 0
(-5202 -2125);
DISPLAY 0.638298 (-5202 -2125);
PAINT MONO (-5202 -2125);
FORCEPROP 2 LAST $XR1 241 
J 0
(-5322 -2125);
DISPLAY 0.638298 (-5322 -2125);
PAINT MONO (-5322 -2125);
FORCEPROP 1 LAST COMMENT_BODY TRUE
J 2
(-4925 -2225);
DISPLAY 0.872340 (-4925 -2225);
PAINT PEACH (-4925 -2225);
DISPLAY INVISIBLE (-4925 -2225);
FORCEPROP 1 LAST OFFPAGE TRUE
J 2
(-5275 -2250);
DISPLAY 0.872340 (-5275 -2250);
PAINT GREEN (-5275 -2250);
DISPLAY INVISIBLE (-5275 -2250);
FORCEPROP 2 LAST CDS_LIB standard
J 2
(-4950 -2125);
DISPLAY INVISIBLE (-4950 -2125);
FORCEPROP 2 LAST PATH I7
J 0
(-5200 -2075);
DISPLAY 1.021277 (-5200 -2075);
DISPLAY INVISIBLE (-5200 -2075);
FORCEADD Q_RES..1
(-4100 -2225);
FORCEPROP 1 LAST PART_NUMBER CS03322FB03
J 0
(-4225 -2175);
DISPLAY 0.404255 (-4225 -2175);
DISPLAY INVISIBLE (-4225 -2175);
FORCEPROP 1 LAST TOLERANCE 1%
J 0
(-3875 -2225);
DISPLAY 0.510638 (-3875 -2225);
FORCEPROP 1 LAST MATERIAL CHIP
J 0
(-3800 -2225);
DISPLAY 0.510638 (-3800 -2225);
FORCEPROP 1 LAST VALUE 33.2
J 2
(-3900 -2225);
DISPLAY 0.510638 (-3900 -2225);
FORCEPROP 1 LAST LOCATION R3114
J 0
(-4300 -2225);
DISPLAY 0.638298 (-4300 -2225);
FORCEPROP 1 LASTPIN (-4200 -2225) $PN 1
J 0
(-4188 -2213);
DISPLAY 0.787234 (-4188 -2213);
PAINT MONO (-4188 -2213);
FORCEPROP 1 LASTPIN (-4000 -2225) $PN 2
J 0
(-4038 -2213);
DISPLAY 0.787234 (-4038 -2213);
PAINT MONO (-4038 -2213);
FORCEPROP 1 LAST WATTAGE 1/16W
J 2
(-4000 -2125);
DISPLAY 0.404255 (-4000 -2125);
DISPLAY INVISIBLE (-4000 -2125);
FORCEPROP 1 LAST PACK_TYPE 0402LF
J 0
(-4225 -2125);
DISPLAY 0.404255 (-4225 -2125);
DISPLAY INVISIBLE (-4225 -2125);
FORCEPROP 2 LAST CDS_LIB pure_quanta
J 0
(-4100 -2225);
DISPLAY INVISIBLE (-4100 -2225);
FORCEPROP 1 LAST PATH I8
J 0
(-4150 -2075);
DISPLAY 0.978723 (-4150 -2075);
PAINT WHITE (-4150 -2075);
DISPLAY INVISIBLE (-4150 -2075);
FORCEPROP 0 LAST $SEC 1
J 0
(-4300 -2175);
DISPLAY 0.680851 (-4300 -2175);
PAINT MONO (-4300 -2175);
DISPLAY INVISIBLE (-4300 -2175);
FORCEPROP 0 LAST CDS_SEC 1
J 0
(-4300 -2175);
DISPLAY 1.021277 (-4300 -2175);
DISPLAY INVISIBLE (-4300 -2175);
FORCEADD Q_RES..1
(-4100 -2125);
FORCEPROP 1 LAST PART_NUMBER CS03322FB03
J 0
(-4225 -2075);
DISPLAY 0.404255 (-4225 -2075);
DISPLAY INVISIBLE (-4225 -2075);
FORCEPROP 1 LAST TOLERANCE 1%
J 0
(-3875 -2125);
DISPLAY 0.510638 (-3875 -2125);
FORCEPROP 1 LAST VALUE 33.2
J 2
(-3900 -2125);
DISPLAY 0.510638 (-3900 -2125);
FORCEPROP 1 LAST MATERIAL CHIP
J 0
(-3800 -2125);
DISPLAY 0.510638 (-3800 -2125);
FORCEPROP 1 LAST LOCATION R3113
J 0
(-4300 -2125);
DISPLAY 0.638298 (-4300 -2125);
FORCEPROP 1 LASTPIN (-4200 -2125) $PN 1
J 0
(-4188 -2113);
DISPLAY 0.787234 (-4188 -2113);
PAINT MONO (-4188 -2113);
FORCEPROP 1 LASTPIN (-4000 -2125) $PN 2
J 0
(-4038 -2113);
DISPLAY 0.787234 (-4038 -2113);
PAINT MONO (-4038 -2113);
FORCEPROP 1 LAST WATTAGE 1/16W
J 2
(-4000 -2025);
DISPLAY 0.404255 (-4000 -2025);
DISPLAY INVISIBLE (-4000 -2025);
FORCEPROP 1 LAST PACK_TYPE 0402LF
J 0
(-4225 -2025);
DISPLAY 0.404255 (-4225 -2025);
DISPLAY INVISIBLE (-4225 -2025);
FORCEPROP 2 LAST CDS_LIB pure_quanta
J 0
(-4100 -2125);
DISPLAY INVISIBLE (-4100 -2125);
FORCEPROP 1 LAST PATH I9
J 0
(-4150 -1975);
DISPLAY 0.978723 (-4150 -1975);
PAINT WHITE (-4150 -1975);
DISPLAY INVISIBLE (-4150 -1975);
FORCEPROP 0 LAST $SEC 1
J 0
(-4300 -2075);
DISPLAY 0.680851 (-4300 -2075);
PAINT MONO (-4300 -2075);
DISPLAY INVISIBLE (-4300 -2075);
FORCEPROP 0 LAST CDS_SEC 1
J 0
(-4300 -2075);
DISPLAY 1.021277 (-4300 -2075);
DISPLAY INVISIBLE (-4300 -2075);
FORCEADD QUANTA_TITLE_BLOCK_C..1
(1650 -3375);
FORCEPROP 0 LAST CDS_CON_LAST_MODIFIED Fri Aug 25 14:04:15 2023
J 0
(-235 -3360);
PAINT MONO (-235 -3360);
DISPLAY INVISIBLE (-235 -3360);
FORCEPROP 2 LAST CUSTOM_TXT_CDS <XR_PAGE_TITLE>
J 0
(-6240 1875);
DISPLAY 0.638298 (-6240 1875);
PAINT PINK (-6240 1875);
DISPLAY INVISIBLE (-6240 1875);
FORCEPROP 2 LAST CUSTOM_TXT_CDS <NAME_2>
J 0
(-1525 -3325);
FORCEPROP 2 LAST CUSTOM_TXT_CDS <CON_LAST_MODIFIED>
J 0
(-235 -3360);
DISPLAY 0.978723 (-235 -3360);
FORCEPROP 2 LAST CUSTOM_TXT_CDS <NAME_1>
J 0
(-1525 -3200);
FORCEPROP 2 LAST CUSTOM_TXT_CDS <Q_PROJ>
J 0
(-732 -3273);
DISPLAY 1.212766 (-732 -3273);
FORCEPROP 2 LAST CUSTOM_TXT_CDS <Q_REV>
J 0
(1466 -3272);
DISPLAY 1.212766 (1466 -3272);
FORCEPROP 2 LAST CUSTOM_TXT_CDS <CON_PAGE_NUM> OF <CON_TOTAL_PAGES>
J 0
(1204 -3357);
DISPLAY 0.978723 (1204 -3357);
FORCEPROP 2 LAST CUSTOM_TXT_CDS <Q_NUMBER>
J 0
(247 -3272);
DISPLAY 1.212766 (247 -3272);
FORCEPROP 1 LAST Q_TITLE POWER CONNECTOR/ISOLATED
J 0
(-7616 -3349);
DISPLAY 2.446809 (-7616 -3349);
PAINT GREEN (-7616 -3349);
FORCEPROP 1 LAST Q_DEPT 
J 1
(-2113 -3326);
DISPLAY 1.957447 (-2113 -3326);
PAINT GREEN (-2113 -3326);
FORCEPROP 2 LAST PAGE_BORDER TRUE
J 0
(-6240 1875);
DISPLAY 0.638298 (-6240 1875);
PAINT PINK (-6240 1875);
DISPLAY INVISIBLE (-6240 1875);
FORCEPROP 1 LAST CDS_LMAN_SYM_OUTLINE -9475,6775,100,-125
J 0
(1650 -3375);
DISPLAY 0.468085 (1650 -3375);
PAINT GREEN (1650 -3375);
DISPLAY INVISIBLE (1650 -3375);
FORCEPROP 2 LAST CDS_LIB pure_quanta
J 0
(1650 -3375);
PAINT MONO (1650 -3375);
DISPLAY INVISIBLE (1650 -3375);
FORCEPROP 1 LAST COMMENT_BODY TRUE
J 0
(1662 -3388);
DISPLAY 0.978723 (1662 -3388);
PAINT GREEN (1662 -3388);
DISPLAY INVISIBLE (1662 -3388);
FORCEPROP 2 LAST CDS_XR_PAGE_TITLE CR-245 : @S9S_MB_2U_LIB.S9S_MB_2U(SCH_1):PAGE245
J 0
(-6240 1875);
DISPLAY 0.638298 (-6240 1875);
PAINT PINK (-6240 1875);
DISPLAY INVISIBLE (-6240 1875);
FORCEADD DNS..2
(-5800 -1725);
PAINT RED (-5800 -1725);
FORCEPROP 2 LAST CDS_LIB mstr_misc
J 0
(-5800 -1725);
DISPLAY INVISIBLE (-5800 -1725);
FORCEPROP 1 LAST COMMENT_BODY TRUE
J 0
(-5800 -1725);
DISPLAY INVISIBLE (-5800 -1725);
FORCEADD DNS..2
(-3175 -4800);
PAINT RED (-3175 -4800);
FORCEPROP 2 LAST CDS_LIB mstr_misc
J 0
(-3175 -4800);
DISPLAY INVISIBLE (-3175 -4800);
FORCEPROP 1 LAST COMMENT_BODY TRUE
J 0
(-3175 -4800);
DISPLAY INVISIBLE (-3175 -4800);
FORCEADD DNS..2
(-2575 -2625);
PAINT RED (-2575 -2625);
FORCEPROP 1 LAST COMMENT_BODY TRUE
J 0
(-2575 -2625);
DISPLAY INVISIBLE (-2575 -2625);
FORCEPROP 2 LAST CDS_LIB mstr_misc
J 0
(-2575 -2625);
DISPLAY INVISIBLE (-2575 -2625);
FORCEADD DNS..2
(-1250 -1700);
PAINT RED (-1250 -1700);
FORCEPROP 2 LAST CDS_LIB mstr_misc
J 0
(-1250 -1700);
DISPLAY INVISIBLE (-1250 -1700);
FORCEPROP 1 LAST COMMENT_BODY TRUE
J 0
(-1250 -1700);
DISPLAY INVISIBLE (-1250 -1700);
FORCEADD DNS..2
(-1000 -1725);
PAINT RED (-1000 -1725);
FORCEPROP 2 LAST CDS_LIB mstr_misc
J 0
(-1000 -1725);
DISPLAY INVISIBLE (-1000 -1725);
FORCEPROP 1 LAST COMMENT_BODY TRUE
J 0
(-1000 -1725);
DISPLAY INVISIBLE (-1000 -1725);
FORCEADD DNS..2
(775 525);
PAINT RED (775 525);
FORCEPROP 2 LAST CDS_LIB mstr_misc
J 0
(775 525);
DISPLAY INVISIBLE (775 525);
FORCEPROP 1 LAST COMMENT_BODY TRUE
J 0
(775 525);
DISPLAY INVISIBLE (775 525);
FORCEADD DNS..2
(775 725);
PAINT RED (775 725);
FORCEPROP 1 LAST COMMENT_BODY TRUE
J 0
(775 725);
DISPLAY INVISIBLE (775 725);
FORCEPROP 2 LAST CDS_LIB mstr_misc
J 0
(775 725);
DISPLAY INVISIBLE (775 725);
FORCEADD DNS..2
(775 875);
PAINT RED (775 875);
FORCEPROP 1 LAST COMMENT_BODY TRUE
J 0
(775 875);
DISPLAY INVISIBLE (775 875);
FORCEPROP 2 LAST CDS_LIB mstr_misc
J 0
(775 875);
DISPLAY INVISIBLE (775 875);
FORCEADD DNS..2
(775 1025);
PAINT RED (775 1025);
FORCEPROP 1 LAST COMMENT_BODY TRUE
J 0
(775 1025);
DISPLAY INVISIBLE (775 1025);
FORCEPROP 2 LAST CDS_LIB mstr_misc
J 0
(775 1025);
DISPLAY INVISIBLE (775 1025);
FORCEADD DNS..2
(775 1175);
PAINT RED (775 1175);
FORCEPROP 1 LAST COMMENT_BODY TRUE
J 0
(775 1175);
DISPLAY INVISIBLE (775 1175);
FORCEPROP 2 LAST CDS_LIB mstr_misc
J 0
(775 1175);
DISPLAY INVISIBLE (775 1175);
FORCEADD DNS..2
(775 1325);
PAINT RED (775 1325);
FORCEPROP 1 LAST COMMENT_BODY TRUE
J 0
(775 1325);
DISPLAY INVISIBLE (775 1325);
FORCEPROP 2 LAST CDS_LIB mstr_misc
J 0
(775 1325);
DISPLAY INVISIBLE (775 1325);
WIRE 16 -1 (-5800 -1475)(-5800 -1600);
WIRE 16 -1 (-2050 -1425)(-2050 -1375);
WIRE 16 -1 (-2050 -2025)(-2050 -1425);
WIRE 16 -1 (-2050 -1425)(-1700 -1425);
WIRE 16 -1 (-1250 -1475)(-1250 -1425);
WIRE 16 -1 (-1250 -1475)(-1000 -1475);
WIRE 16 -1 (-1250 -1575)(-1250 -1475);
WIRE 16 -1 (-2325 1650)(-2575 1650);
WIRE 16 -1 (-1175 2600)(-1175 2450);
WIRE 16 -1 (-5725 -2350)(-5725 -2575);
WIRE 16 -1 (-3825 300)(-3825 75);
WIRE 16 -1 (-3825 350)(-3825 300);
WIRE 16 -1 (-3825 300)(-3600 300);
WIRE 16 -1 (-2975 -2325)(-2975 -2375);
WIRE 16 -1 (-2950 -2325)(-2975 -2325);
WIRE 16 -1 (-1700 -1700)(-1700 -1800);
WIRE 16 -1 (1200 550)(1200 400);
WIRE 16 -1 (1200 725)(1200 550);
WIRE 16 -1 (850 550)(1200 550);
WIRE 16 -1 (850 1325)(1200 1325);
WIRE 16 -1 (850 1175)(1200 1175);
WIRE 16 -1 (1200 1325)(1200 1175);
WIRE 16 -1 (850 1025)(1200 1025);
WIRE 16 -1 (1200 1175)(1200 1025);
WIRE 16 -1 (850 875)(1200 875);
WIRE 16 -1 (1200 1025)(1200 875);
WIRE 16 -1 (1200 875)(1200 725);
WIRE 16 -1 (850 725)(1200 725);
WIRE 16 -1 (-450 1325)(650 1325);
FORCEPROP 2 LAST SIG_NAME RST_SMB_SWITCH_R_N
J 0
(-210 1335);
DISPLAY 0.638298 (-210 1335);
PAINT WHITE (-210 1335);
WIRE 16 -1 (-450 1175)(650 1175);
FORCEPROP 2 LAST SIG_NAME PDB_PRSNT_N
J 0
(-210 1185);
DISPLAY 0.638298 (-210 1185);
PAINT WHITE (-210 1185);
WIRE 16 -1 (650 550)(-450 550);
FORCEPROP 2 LAST SIG_NAME FM_AC_PWR_BTN_PDB_N
J 0
(-210 560);
DISPLAY 0.638298 (-210 560);
PAINT WHITE (-210 560);
WIRE 16 -1 (650 875)(-450 875);
FORCEPROP 2 LAST SIG_NAME FM_FAN_PWR_EN_R
J 0
(-210 885);
DISPLAY 0.638298 (-210 885);
PAINT WHITE (-210 885);
WIRE 16 -1 (650 725)(-450 725);
FORCEPROP 2 LAST SIG_NAME FM_GPU_HSC_EN_BUF_R1
J 0
(-210 735);
DISPLAY 0.638298 (-210 735);
PAINT WHITE (-210 735);
WIRE 16 -1 (650 1025)(-450 1025);
FORCEPROP 2 LAST SIG_NAME HPDB_HSC_PWRGD_R
J 0
(-210 1035);
DISPLAY 0.638298 (-210 1035);
PAINT WHITE (-210 1035);
WIRE 16 2175 (-850 275)(1425 275);
WIRE 16 2175 (1425 1475)(1425 275);
WIRE 16 2175 (-850 1475)(-850 275);
WIRE 16 2175 (-850 1475)(1425 1475);
WIRE 16 -1 (975 -2125)(-425 -2125);
FORCEPROP 2 LAST SIG_NAME SMB_FAN_3V3AUX_BUF_R_SCL
J 0
(-85 -2115);
DISPLAY 0.638298 (-85 -2115);
PAINT WHITE (-85 -2115);
WIRE 16 -1 (975 -2225)(-425 -2225);
FORCEPROP 2 LAST SIG_NAME SMB_FAN_3V3AUX_BUF_R_SDA
J 0
(-85 -2215);
DISPLAY 0.638298 (-85 -2215);
PAINT WHITE (-85 -2215);
WIRE 16 2175 (-1375 2800)(-925 2800);
WIRE 16 2175 (-925 2800)(-925 2150);
WIRE 16 2175 (-1375 2800)(-1375 2150);
WIRE 16 2175 (-1375 2150)(-925 2150);
WIRE 16 -1 (-400 2050)(-2800 2050);
FORCEPROP 2 LAST SIG_NAME SMB_FAN_3V3AUX_BUF_R_SCL
J 0
(-2560 2060);
DISPLAY 0.638298 (-2560 2060);
PAINT WHITE (-2560 2060);
WIRE 16 -1 (-400 2000)(-2800 2000);
FORCEPROP 2 LAST SIG_NAME SMB_FAN_3V3AUX_BUF_R_SDA
J 0
(-2560 2010);
DISPLAY 0.638298 (-2560 2010);
PAINT WHITE (-2560 2010);
WIRE 16 -1 (-1500 1950)(-375 1950);
FORCEPROP 2 LAST SIG_NAME HPDB_HSC_PWRGD
J 0
(-1085 1960);
DISPLAY 0.638298 (-1085 1960);
PAINT WHITE (-1085 1960);
WIRE 16 -1 (-1500 1850)(-375 1850);
FORCEPROP 2 LAST SIG_NAME FM_GPU_HSC_EN_BUF
J 0
(-1085 1860);
DISPLAY 0.638298 (-1085 1860);
PAINT WHITE (-1085 1860);
WIRE 16 -1 (-1175 1900)(-375 1900);
FORCEPROP 2 LAST SIG_NAME FM_FAN_PWR_EN
J 0
(-1085 1910);
DISPLAY 0.638298 (-1085 1910);
PAINT WHITE (-1085 1910);
WIRE 16 -1 (-1175 2250)(-1175 1900);
WIRE 16 -1 (-1500 1900)(-1175 1900);
WIRE 16 -1 (-2800 1800)(-375 1800);
FORCEPROP 2 LAST SIG_NAME PDB_PRSNT_N
J 0
(-2560 1810);
DISPLAY 0.638298 (-2560 1810);
PAINT WHITE (-2560 1810);
WIRE 16 -1 (-1700 1950)(-2800 1950);
FORCEPROP 2 LAST SIG_NAME HPDB_HSC_PWRGD_R
J 0
(-2560 1960);
DISPLAY 0.638298 (-2560 1960);
PAINT WHITE (-2560 1960);
FORCEPROP 2 LASTPROP $XR0 245 
J 0
(-2686 1960);
DISPLAY 0.638298 (-2686 1960);
PAINT MONO (-2686 1960);
WIRE 16 -1 (-1700 1900)(-2800 1900);
FORCEPROP 2 LAST SIG_NAME FM_FAN_PWR_EN_R
J 0
(-2560 1910);
DISPLAY 0.638298 (-2560 1910);
PAINT WHITE (-2560 1910);
FORCEPROP 2 LASTPROP $XR0 245 
J 0
(-2686 1910);
DISPLAY 0.638298 (-2686 1910);
PAINT MONO (-2686 1910);
WIRE 16 -1 (-1700 1850)(-2800 1850);
FORCEPROP 2 LAST SIG_NAME FM_GPU_HSC_EN_BUF_R1
J 0
(-2560 1860);
DISPLAY 0.638298 (-2560 1860);
PAINT WHITE (-2560 1860);
FORCEPROP 2 LASTPROP $XR0 245 
J 0
(-2686 1860);
DISPLAY 0.638298 (-2686 1860);
PAINT MONO (-2686 1860);
WIRE 16 -1 (-2575 1650)(-2800 1650);
WIRE 16 -1 (-2800 1600)(-2575 1600);
WIRE 16 -1 (-2575 1600)(-2575 1650);
WIRE 16 -1 (-2575 1550)(-2800 1550);
WIRE 16 -1 (-2575 1550)(-2575 1600);
WIRE 16 -1 (-2800 1500)(-2575 1500);
WIRE 16 -1 (-2575 1500)(-2575 1550);
WIRE 16 -1 (-2575 1450)(-2800 1450);
WIRE 16 -1 (-2575 1450)(-2575 1500);
WIRE 16 -1 (-2800 1400)(-2575 1400);
WIRE 16 -1 (-2575 1400)(-2575 1450);
WIRE 16 -1 (-2575 1350)(-2800 1350);
WIRE 16 -1 (-2575 1350)(-2575 1400);
WIRE 16 -1 (-2800 1300)(-2575 1300);
WIRE 16 -1 (-2575 1300)(-2575 1350);
WIRE 16 -1 (-2575 1150)(-2800 1150);
WIRE 16 -1 (-2575 1150)(-2575 1300);
WIRE 16 -1 (-2800 1100)(-2575 1100);
WIRE 16 -1 (-2575 1100)(-2575 1150);
WIRE 16 -1 (-2575 1050)(-2800 1050);
WIRE 16 -1 (-2575 1050)(-2575 1100);
WIRE 16 -1 (-2800 1000)(-2575 1000);
WIRE 16 -1 (-2575 1000)(-2575 1050);
WIRE 16 -1 (-2575 950)(-2800 950);
WIRE 16 -1 (-2575 950)(-2575 1000);
WIRE 16 -1 (-2800 900)(-2575 900);
WIRE 16 -1 (-2575 900)(-2575 950);
WIRE 16 -1 (-2575 850)(-2800 850);
WIRE 16 -1 (-2575 850)(-2575 900);
WIRE 16 -1 (-2800 800)(-2575 800);
WIRE 16 -1 (-2575 800)(-2575 850);
WIRE 16 -1 (-2575 650)(-2800 650);
WIRE 16 -1 (-2575 650)(-2575 800);
WIRE 16 -1 (-2800 600)(-2575 600);
WIRE 16 -1 (-2575 600)(-2575 650);
WIRE 16 -1 (-2575 550)(-2800 550);
WIRE 16 -1 (-2575 550)(-2575 600);
WIRE 16 -1 (-2800 500)(-2575 500);
WIRE 16 -1 (-2575 500)(-2575 550);
WIRE 16 -1 (-2575 450)(-2800 450);
WIRE 16 -1 (-2575 450)(-2575 500);
WIRE 16 -1 (-2800 400)(-2575 400);
WIRE 16 -1 (-2575 400)(-2575 450);
WIRE 16 -1 (-2575 350)(-2800 350);
WIRE 16 -1 (-2575 350)(-2575 400);
WIRE 16 -1 (-2575 300)(-2575 350);
WIRE 16 -1 (-2800 300)(-2575 300);
WIRE 16 -1 (-3600 1800)(-3825 1800);
WIRE 16 -1 (-3600 1650)(-3825 1650);
WIRE 16 -1 (-3825 1800)(-3825 1650);
WIRE 16 -1 (-3825 1650)(-3825 1600);
WIRE 16 -1 (-3825 1600)(-3600 1600);
WIRE 16 -1 (-3825 1600)(-3825 1550);
WIRE 16 -1 (-3600 1550)(-3825 1550);
WIRE 16 -1 (-3825 1500)(-3600 1500);
WIRE 16 -1 (-3825 1550)(-3825 1500);
WIRE 16 -1 (-3825 1500)(-3825 1450);
WIRE 16 -1 (-3600 1450)(-3825 1450);
WIRE 16 -1 (-3825 1450)(-3825 1400);
WIRE 16 -1 (-3825 1400)(-3600 1400);
WIRE 16 -1 (-3825 1400)(-3825 1350);
WIRE 16 -1 (-3600 1350)(-3825 1350);
WIRE 16 -1 (-3825 1350)(-3825 1300);
WIRE 16 -1 (-3825 1300)(-3600 1300);
WIRE 16 -1 (-3600 1150)(-3825 1150);
WIRE 16 -1 (-3825 1300)(-3825 1150);
WIRE 16 -1 (-3825 1150)(-3825 1100);
WIRE 16 -1 (-3825 1100)(-3600 1100);
WIRE 16 -1 (-3825 1100)(-3825 1050);
WIRE 16 -1 (-3600 1050)(-3825 1050);
WIRE 16 -1 (-3825 1000)(-3600 1000);
WIRE 16 -1 (-3825 1050)(-3825 1000);
WIRE 16 -1 (-3825 1000)(-3825 950);
WIRE 16 -1 (-3600 950)(-3825 950);
WIRE 16 -1 (-3825 950)(-3825 900);
WIRE 16 -1 (-3825 900)(-3600 900);
WIRE 16 -1 (-3825 900)(-3825 850);
WIRE 16 -1 (-3600 850)(-3825 850);
WIRE 16 -1 (-3825 850)(-3825 800);
WIRE 16 -1 (-3825 800)(-3600 800);
WIRE 16 -1 (-3600 650)(-3825 650);
WIRE 16 -1 (-3825 800)(-3825 650);
WIRE 16 -1 (-3825 650)(-3825 600);
WIRE 16 -1 (-3825 600)(-3600 600);
WIRE 16 -1 (-3825 600)(-3825 550);
WIRE 16 -1 (-3600 550)(-3825 550);
WIRE 16 -1 (-3825 500)(-3600 500);
WIRE 16 -1 (-3825 550)(-3825 500);
WIRE 16 -1 (-3825 500)(-3825 450);
WIRE 16 -1 (-3600 450)(-3825 450);
WIRE 16 -1 (-3825 450)(-3825 400);
WIRE 16 -1 (-3825 400)(-3600 400);
WIRE 16 -1 (-3825 400)(-3825 350);
WIRE 16 -1 (-3600 350)(-3825 350);
WIRE 16 -1 (-5100 2000)(-3600 2000);
FORCEPROP 0 LAST CDS_PHYS_NET_NAME FM_AC_PWR_BTN_PDB_N
J 0
(-4460 2034);
PAINT MONO (-4460 2034);
DISPLAY INVISIBLE (-4460 2034);
FORCEPROP 2 LAST SIG_NAME FM_AC_PWR_BTN_PDB_N
J 0
(-4635 2010);
DISPLAY 0.638298 (-4635 2010);
PAINT RED (-4635 2010);
FORCEPROP 2 LASTPROP $XR0 245 
J 0
(-4731 2010);
DISPLAY 0.638298 (-4731 2010);
PAINT MONO (-4731 2010);
WIRE 16 -1 (-5100 1900)(-3600 1900);
FORCEPROP 2 LAST SIG_NAME RST_SMB_SWITCH_R_N
J 0
(-4635 1910);
DISPLAY 0.638298 (-4635 1910);
PAINT WHITE (-4635 1910);
FORCEPROP 2 LASTPROP $XR0 245 
J 0
(-4731 1910);
DISPLAY 0.638298 (-4731 1910);
PAINT MONO (-4731 1910);
WIRE 16 -1 (-5300 1900)(-6450 1900);
FORCEPROP 2 LAST SIG_NAME RST_SMB_SWITCH_N
J 0
(-6135 1910);
DISPLAY 0.638298 (-6135 1910);
PAINT WHITE (-6135 1910);
WIRE 16 -1 (-6450 2000)(-5300 2000);
FORCEPROP 0 LAST CDS_PHYS_NET_NAME FM_AC_PWR_BTN_R_N
J 0
(-5810 2034);
PAINT MONO (-5810 2034);
DISPLAY INVISIBLE (-5810 2034);
FORCEPROP 2 LAST SIG_NAME FM_AC_PWR_BTN_R_N
J 0
(-6135 2010);
DISPLAY 0.638298 (-6135 2010);
PAINT RED (-6135 2010);
WIRE 16 -1 (-6450 2050)(-3600 2050);
FORCEPROP 0 LAST CDS_PHYS_NET_NAME TP_J45_A1
J 0
(-4110 2084);
PAINT MONO (-4110 2084);
DISPLAY INVISIBLE (-4110 2084);
FORCEPROP 2 LAST SIG_NAME TP_J45_A1
J 0
(-6135 2060);
DISPLAY 0.638298 (-6135 2060);
PAINT RED (-6135 2060);
WIRE 16 -1 (-3600 1950)(-6450 1950);
FORCEPROP 2 LAST SIG_NAME P3V3_PDB_AUX_ADC
J 0
(-6135 1960);
DISPLAY 0.638298 (-6135 1960);
PAINT WHITE (-6135 1960);
WIRE 16 -1 (-3600 1850)(-6450 1850);
FORCEPROP 2 LAST SIG_NAME PWRGD_P3V3_AUX_PDB_BUF
J 0
(-6135 1860);
DISPLAY 0.638298 (-6135 1860);
PAINT WHITE (-6135 1860);
WIRE 16 -1 (-1000 -1600)(-1000 -1475);
WIRE 16 2175 (-1450 -1250)(-750 -1250);
WIRE 16 2175 (-750 -1250)(-750 -1875);
WIRE 16 2175 (-1450 -1250)(-1450 -1875);
WIRE 16 2175 (-1450 -1875)(-750 -1875);
WIRE 16 -1 (-1000 -2225)(-625 -2225);
WIRE 16 -1 (-1000 -1800)(-1000 -2225);
WIRE 16 -1 (-2150 -2225)(-1950 -2225);
FORCEPROP 2 LAST SIG_NAME SMB_FAN_3V3AUX_BUF_SDA
J 0
(-1935 -2215);
DISPLAY 0.638298 (-1935 -2215);
PAINT WHITE (-1935 -2215);
WIRE 16 -1 (-1950 -2225)(-1000 -2225);
WIRE 16 -1 (-1950 -2650)(-2475 -2650);
WIRE 16 -1 (-1950 -2650)(-1950 -2225);
WIRE 16 -1 (-1250 -2125)(-625 -2125);
WIRE 16 -1 (-1250 -1775)(-1250 -2125);
WIRE 16 -1 (-2150 -2125)(-2075 -2125);
WIRE 16 -1 (-2075 -2125)(-1250 -2125);
FORCEPROP 2 LAST SIG_NAME SMB_FAN_3V3AUX_BUF_SCL
J 0
(-1935 -2115);
DISPLAY 0.638298 (-1935 -2115);
PAINT WHITE (-1935 -2115);
WIRE 16 -1 (-2075 -2575)(-2075 -2125);
WIRE 16 -1 (-2475 -2575)(-2075 -2575);
WIRE 16 -1 (-1700 -1425)(-1700 -1500);
WIRE 16 -1 (-2150 -2025)(-2050 -2025);
WIRE 16 -1 (-3075 -2575)(-2675 -2575);
WIRE 16 -1 (-3075 -2575)(-3075 -2125);
WIRE 16 -1 (-3075 -2125)(-2950 -2125);
WIRE 16 -1 (-4000 -2125)(-3075 -2125);
FORCEPROP 2 LAST SIG_NAME SMB_FAN_3V3AUX_R_SCL
J 0
(-3685 -2115);
DISPLAY 0.638298 (-3685 -2115);
PAINT WHITE (-3685 -2115);
WIRE 16 -1 (-2675 -2650)(-3200 -2650);
WIRE 16 -1 (-3200 -2650)(-3200 -2225);
WIRE 16 -1 (-3200 -2225)(-2950 -2225);
WIRE 16 -1 (-4000 -2225)(-3200 -2225);
FORCEPROP 2 LAST SIG_NAME SMB_FAN_3V3AUX_R_SDA
J 0
(-3685 -2215);
DISPLAY 0.638298 (-3685 -2215);
PAINT WHITE (-3685 -2215);
WIRE 16 -1 (-2950 -2025)(-4000 -2025);
FORCEPROP 2 LAST SIG_NAME FM_MB_PDB_SMB9_R_EN
J 0
(-3685 -2015);
DISPLAY 0.638298 (-3685 -2015);
PAINT WHITE (-3685 -2015);
WIRE 16 -1 (-4900 -2125)(-4200 -2125);
FORCEPROP 2 LAST SIG_NAME SMB_FAN_3V3AUX_SCL
J 0
(-4885 -2115);
DISPLAY 0.638298 (-4885 -2115);
PAINT WHITE (-4885 -2115);
WIRE 16 -1 (-4900 -2225)(-4200 -2225);
FORCEPROP 2 LAST SIG_NAME SMB_FAN_3V3AUX_SDA
J 0
(-4885 -2215);
DISPLAY 0.638298 (-4885 -2215);
PAINT WHITE (-4885 -2215);
WIRE 16 2175 (-6975 -2650)(-5350 -2650);
WIRE 16 2175 (-5350 -1300)(-5350 -2650);
WIRE 16 2175 (-6975 -1300)(-6975 -2650);
WIRE 16 2175 (-6975 -1300)(-5350 -1300);
WIRE 16 -1 (-5725 -2025)(-5725 -2150);
WIRE 16 -1 (-5725 -2025)(-4200 -2025);
WIRE 16 -1 (-5800 -1800)(-5800 -2025);
WIRE 16 -1 (-5800 -2025)(-5725 -2025);
WIRE 16 -1 (-6525 -2025)(-5800 -2025);
FORCEPROP 2 LAST SIG_NAME FM_PDB_BUF_EN_R
J 0
(-6460 -2015);
DISPLAY 0.638298 (-6460 -2015);
PAINT WHITE (-6460 -2015);
DOT 1 (-5800 -2025);
DOT 1 (-5725 -2025);
DOT 1 (-3825 300);
DOT 1 (-3825 350);
DOT 1 (-3825 400);
DOT 1 (-3825 450);
DOT 1 (-3825 500);
DOT 1 (-3825 550);
DOT 1 (-3825 600);
DOT 1 (-3825 650);
DOT 1 (-3825 800);
DOT 1 (-3825 850);
DOT 1 (-3825 900);
DOT 1 (-3825 950);
DOT 1 (-3825 1000);
DOT 1 (-3825 1050);
DOT 1 (-3825 1100);
DOT 1 (-3825 1150);
DOT 1 (-3075 -2125);
DOT 1 (-3200 -2225);
DOT 1 (-2075 -2125);
DOT 1 (-1950 -2225);
DOT 1 (-2050 -1425);
DOT 1 (-2575 350);
DOT 1 (-2575 400);
DOT 1 (-2575 450);
DOT 1 (-2575 500);
DOT 1 (-2575 550);
DOT 1 (-2575 650);
DOT 1 (-2575 600);
DOT 1 (-2575 800);
DOT 1 (-2575 850);
DOT 1 (-2575 900);
DOT 1 (-2575 950);
DOT 1 (-2575 1000);
DOT 1 (-2575 1050);
DOT 1 (-2575 1100);
DOT 1 (-2575 1150);
DOT 1 (-1000 -2225);
DOT 1 (-1250 -2125);
DOT 1 (-1250 -1475);
DOT 1 (-3825 1300);
DOT 1 (-3825 1350);
DOT 1 (-3825 1400);
DOT 1 (-3825 1450);
DOT 1 (-3825 1500);
DOT 1 (-3825 1550);
DOT 1 (-3825 1600);
DOT 1 (-3825 1650);
DOT 1 (-2575 1350);
DOT 1 (-2575 1300);
DOT 1 (-2575 1450);
DOT 1 (-2575 1400);
DOT 1 (-2575 1600);
DOT 1 (-2575 1500);
DOT 1 (-2575 1550);
DOT 1 (-2575 1650);
DOT 1 (-1175 1900);
DOT 1 (1200 550);
DOT 1 (1200 725);
DOT 1 (1200 875);
DOT 1 (1200 1175);
DOT 1 (1200 1025);
FORCENOTE
20220805 DEPOP R2950, ADD R4769
(-6900 -2950) 0;
DISPLAY LEFT (-6900 -2950);
DISPLAY 1.063830 (-6900 -2950);
PAINT WHITE (-6900 -2950);
FORCENOTE
20220725 DEPOP U190,R2794,R2793
(-6900 -2875) 0;
DISPLAY LEFT (-6900 -2875);
DISPLAY 1.063830 (-6900 -2875);
PAINT WHITE (-6900 -2875);
FORCENOTE
20220318 POP R2950,R2793,U190
(-6900 -2800) 0;
DISPLAY LEFT (-6900 -2800);
DISPLAY 1.063830 (-6900 -2800);
PAINT WHITE (-6900 -2800);
FORCENOTE
20220315 DEPOP R2950,R2793,U190
(-6900 -2725) 0;
DISPLAY LEFT (-6900 -2725);
DISPLAY 1.063830 (-6900 -2725);
PAINT WHITE (-6900 -2725);
FORCENOTE
20221215 DEPOP R2805,2807
(-1900 -1150) 0;
DISPLAY LEFT (-1900 -1150);
DISPLAY 1.595745 (-1900 -1150);
PAINT PINK (-1900 -1150);
FORCENOTE
PU IN VPDB
(-725 -1300) 0;
DISPLAY LEFT (-725 -1300);
DISPLAY 1.021277 (-725 -1300);
PAINT PINK (-725 -1300);
FORCENOTE
20210616 MODIFY FOR GT
(-7475 2950) 0;
DISPLAY LEFT (-7475 2950);
DISPLAY 2.510638 (-7475 2950);
PAINT PINK (-7475 2950);
FORCENOTE
20220726 ADD R4701
(-1675 2825) 0;
DISPLAY LEFT (-1675 2825);
DISPLAY 1.276596 (-1675 2825);
PAINT PINK (-1675 2825);
FORCENOTE
20211206 ADD FOR EMI
(-475 200) 0;
DISPLAY LEFT (-475 200);
DISPLAY 1.595745 (-475 200);
PAINT PINK (-475 200);
QUIT
